(kicad_sch (version 20230121) (generator eeschema)

  (paper "A3")

  (title_block
    (title "Data Center RDIMM DDR4 Tester")
    (date "2024-09-30")
    (rev "1.2.4")
    (company "Antmicro Ltd.")
    (comment 1 "www.antmicro.com")
    (comment 2 "Antmicro Ltd")
  )

  (junction (at 62.23 60.96) (diameter 0) (color 0 0 0 0)
  )
  (junction (at 119.38 158.75) (diameter 0) (color 0 0 0 0)
  )
  (junction (at 338.455 60.325) (diameter 0) (color 0 0 0 0)
  )
  (junction (at 309.88 67.945) (diameter 0) (color 0 0 0 0)
  )
  (junction (at 259.08 245.11) (diameter 0) (color 0 0 0 0)
  )
  (junction (at 375.92 99.06) (diameter 0) (color 0 0 0 0)
  )
  (junction (at 55.245 63.5) (diameter 0) (color 0 0 0 0)
  )
  (junction (at 300.355 70.485) (diameter 0) (color 0 0 0 0)
  )
  (junction (at 387.35 67.31) (diameter 0) (color 0 0 0 0)
  )
  (junction (at 328.295 149.86) (diameter 0) (color 0 0 0 0)
  )
  (junction (at 328.295 179.705) (diameter 0) (color 0 0 0 0)
  )
  (junction (at 347.345 149.86) (diameter 0) (color 0 0 0 0)
  )
  (junction (at 222.25 160.02) (diameter 0) (color 0 0 0 0)
  )
  (junction (at 224.155 167.64) (diameter 0) (color 0 0 0 0)
  )
  (junction (at 328.93 62.865) (diameter 0) (color 0 0 0 0)
  )
  (junction (at 387.35 99.06) (diameter 0) (color 0 0 0 0)
  )
  (junction (at 67.31 114.3) (diameter 0) (color 0 0 0 0)
  )
  (junction (at 353.695 169.545) (diameter 0) (color 0 0 0 0)
  )
  (junction (at 48.26 60.96) (diameter 0) (color 0 0 0 0)
  )
  (junction (at 68.58 158.75) (diameter 0) (color 0 0 0 0)
  )
  (junction (at 281.305 75.565) (diameter 0) (color 0 0 0 0)
  )
  (junction (at 78.105 142.24) (diameter 0) (color 0 0 0 0)
  )
  (junction (at 111.76 158.75) (diameter 0) (color 0 0 0 0)
  )
  (junction (at 347.98 57.785) (diameter 0) (color 0 0 0 0)
  )
  (junction (at 243.84 80.01) (diameter 0) (color 0 0 0 0)
  )
  (junction (at 334.645 149.86) (diameter 0) (color 0 0 0 0)
  )
  (junction (at 353.695 149.86) (diameter 0) (color 0 0 0 0)
  )
  (junction (at 76.2 158.75) (diameter 0) (color 0 0 0 0)
  )
  (junction (at 315.595 149.86) (diameter 0) (color 0 0 0 0)
  )
  (junction (at 347.345 172.085) (diameter 0) (color 0 0 0 0)
  )
  (junction (at 290.83 73.025) (diameter 0) (color 0 0 0 0)
  )
  (junction (at 321.945 149.86) (diameter 0) (color 0 0 0 0)
  )
  (junction (at 78.74 57.15) (diameter 0) (color 0 0 0 0)
  )
  (junction (at 78.74 50.8) (diameter 0) (color 0 0 0 0)
  )
  (junction (at 60.96 158.75) (diameter 0) (color 0 0 0 0)
  )
  (junction (at 340.995 174.625) (diameter 0) (color 0 0 0 0)
  )
  (junction (at 267.335 245.11) (diameter 0) (color 0 0 0 0)
  )
  (junction (at 48.26 74.295) (diameter 0) (color 0 0 0 0)
  )
  (junction (at 319.405 65.405) (diameter 0) (color 0 0 0 0)
  )
  (junction (at 334.645 177.165) (diameter 0) (color 0 0 0 0)
  )
  (junction (at 243.84 82.55) (diameter 0) (color 0 0 0 0)
  )
  (junction (at 55.245 74.295) (diameter 0) (color 0 0 0 0)
  )
  (junction (at 243.84 87.63) (diameter 0) (color 0 0 0 0)
  )
  (junction (at 259.08 261.62) (diameter 0) (color 0 0 0 0)
  )
  (junction (at 226.695 165.1) (diameter 0) (color 0 0 0 0)
  )
  (junction (at 321.945 182.245) (diameter 0) (color 0 0 0 0)
  )
  (junction (at 340.995 149.86) (diameter 0) (color 0 0 0 0)
  )
  (junction (at 315.595 184.785) (diameter 0) (color 0 0 0 0)
  )
  (junction (at 46.99 114.3) (diameter 0) (color 0 0 0 0)
  )
  (junction (at 41.275 74.295) (diameter 0) (color 0 0 0 0)
  )
  (junction (at 243.84 85.09) (diameter 0) (color 0 0 0 0)
  )
  (junction (at 229.87 152.4) (diameter 0) (color 0 0 0 0)
  )
  (junction (at 26.035 60.96) (diameter 0) (color 0 0 0 0)
  )
  (junction (at 41.275 63.5) (diameter 0) (color 0 0 0 0)
  )
  (junction (at 78.105 139.7) (diameter 0) (color 0 0 0 0)
  )
  (junction (at 375.92 67.31) (diameter 0) (color 0 0 0 0)
  )

  (no_connect (at 121.285 104.14))
  (no_connect (at 121.285 140.97))
  (no_connect (at 121.285 87.63))
  (no_connect (at 121.285 120.65))
  (no_connect (at 80.645 95.25))
  (no_connect (at 121.285 60.96))
  (no_connect (at 80.645 100.33))
  (no_connect (at 121.285 99.06))
  (no_connect (at 121.285 109.22))
  (no_connect (at 121.285 130.81))
  (no_connect (at 121.285 123.19))
  (no_connect (at 237.49 172.72))
  (no_connect (at 121.285 66.04))
  (no_connect (at 80.645 97.79))
  (no_connect (at 210.82 85.09))
  (no_connect (at 121.285 106.68))
  (no_connect (at 121.285 133.35))
  (no_connect (at 121.285 82.55))
  (no_connect (at 121.285 101.6))
  (no_connect (at 121.285 111.76))
  (no_connect (at 121.285 138.43))
  (no_connect (at 121.285 125.73))
  (no_connect (at 121.285 68.58))
  (no_connect (at 121.285 128.27))
  (no_connect (at 237.49 175.26))
  (no_connect (at 121.285 90.17))

  (wire (pts (xy 27.94 224.79) (xy 54.61 224.79))
    (stroke (width 0) (type default))
  )
  (wire (pts (xy 235.585 184.785) (xy 235.585 182.88))
    (stroke (width 0) (type default))
  )
  (wire (pts (xy 78.74 50.8) (xy 80.645 50.8))
    (stroke (width 0) (type default))
  )
  (wire (pts (xy 229.87 152.4) (xy 229.87 147.955))
    (stroke (width 0) (type default))
  )
  (wire (pts (xy 375.92 99.06) (xy 375.92 87.63))
    (stroke (width 0) (type default))
  )
  (wire (pts (xy 78.105 139.7) (xy 80.645 139.7))
    (stroke (width 0) (type default))
  )
  (wire (pts (xy 387.35 99.06) (xy 387.35 87.63))
    (stroke (width 0) (type default))
  )
  (wire (pts (xy 68.58 158.75) (xy 76.2 158.75))
    (stroke (width 0) (type default))
  )
  (wire (pts (xy 58.42 255.27) (xy 62.23 255.27))
    (stroke (width 0) (type default))
  )
  (wire (pts (xy 259.08 242.57) (xy 259.08 245.11))
    (stroke (width 0) (type default))
  )
  (wire (pts (xy 147.32 233.68) (xy 152.4 233.68))
    (stroke (width 0) (type default))
  )
  (wire (pts (xy 62.23 66.04) (xy 62.23 60.96))
    (stroke (width 0) (type default))
  )
  (wire (pts (xy 300.355 70.485) (xy 300.355 80.645))
    (stroke (width 0) (type default))
  )
  (wire (pts (xy 136.525 55.88) (xy 148.59 55.88))
    (stroke (width 0) (type default))
  )
  (wire (pts (xy 252.095 234.95) (xy 259.08 234.95))
    (stroke (width 0) (type default))
  )
  (polyline (pts (xy 177.8 212.09) (xy 177.8 12.065))
    (stroke (width 0) (type default))
  )

  (wire (pts (xy 136.525 85.09) (xy 148.59 85.09))
    (stroke (width 0) (type default))
  )
  (wire (pts (xy 222.25 160.02) (xy 219.075 160.02))
    (stroke (width 0) (type default))
  )
  (wire (pts (xy 46.99 105.41) (xy 46.99 114.3))
    (stroke (width 0) (type default))
  )
  (wire (pts (xy 26.035 60.96) (xy 26.035 63.5))
    (stroke (width 0) (type default))
  )
  (wire (pts (xy 136.525 58.42) (xy 148.59 58.42))
    (stroke (width 0) (type default))
  )
  (wire (pts (xy 204.47 64.77) (xy 210.82 64.77))
    (stroke (width 0) (type default))
  )
  (wire (pts (xy 136.525 77.47) (xy 148.59 77.47))
    (stroke (width 0) (type default))
  )
  (wire (pts (xy 259.08 234.95) (xy 259.08 237.49))
    (stroke (width 0) (type default))
  )
  (wire (pts (xy 46.99 105.41) (xy 80.645 105.41))
    (stroke (width 0) (type default))
  )
  (wire (pts (xy 387.35 87.63) (xy 384.175 87.63))
    (stroke (width 0) (type default))
  )
  (wire (pts (xy 136.525 80.01) (xy 148.59 80.01))
    (stroke (width 0) (type default))
  )
  (wire (pts (xy 59.055 235.585) (xy 62.865 235.585))
    (stroke (width 0) (type default))
  )
  (wire (pts (xy 83.185 224.79) (xy 109.855 224.79))
    (stroke (width 0) (type default))
  )
  (wire (pts (xy 347.98 46.355) (xy 347.98 39.37))
    (stroke (width 0) (type default))
  )
  (wire (pts (xy 62.23 60.96) (xy 80.645 60.96))
    (stroke (width 0) (type default))
  )
  (wire (pts (xy 28.575 244.475) (xy 55.245 244.475))
    (stroke (width 0) (type default))
  )
  (wire (pts (xy 236.22 80.01) (xy 243.84 80.01))
    (stroke (width 0) (type default))
  )
  (wire (pts (xy 328.93 46.355) (xy 328.93 38.735))
    (stroke (width 0) (type default))
  )
  (wire (pts (xy 204.47 69.85) (xy 210.82 69.85))
    (stroke (width 0) (type default))
  )
  (wire (pts (xy 76.2 158.75) (xy 83.82 158.75))
    (stroke (width 0) (type default))
  )
  (wire (pts (xy 387.35 55.88) (xy 384.175 55.88))
    (stroke (width 0) (type default))
  )
  (wire (pts (xy 83.82 158.75) (xy 83.82 161.29))
    (stroke (width 0) (type default))
  )
  (wire (pts (xy 236.22 90.17) (xy 238.76 90.17))
    (stroke (width 0) (type default))
  )
  (wire (pts (xy 121.285 53.34) (xy 131.445 53.34))
    (stroke (width 0) (type default))
  )
  (wire (pts (xy 353.695 160.02) (xy 353.695 169.545))
    (stroke (width 0) (type default))
  )
  (wire (pts (xy 309.88 51.435) (xy 309.88 67.945))
    (stroke (width 0) (type default))
  )
  (wire (pts (xy 340.995 154.94) (xy 340.995 149.86))
    (stroke (width 0) (type default))
  )
  (wire (pts (xy 256.54 261.62) (xy 259.08 261.62))
    (stroke (width 0) (type default))
  )
  (wire (pts (xy 238.76 90.17) (xy 238.76 92.71))
    (stroke (width 0) (type default))
  )
  (wire (pts (xy 259.08 77.47) (xy 259.08 75.565))
    (stroke (width 0) (type default))
  )
  (wire (pts (xy 347.345 149.86) (xy 353.695 149.86))
    (stroke (width 0) (type default))
  )
  (wire (pts (xy 131.445 77.47) (xy 121.285 77.47))
    (stroke (width 0) (type default))
  )
  (wire (pts (xy 67.31 114.3) (xy 67.31 115.57))
    (stroke (width 0) (type default))
  )
  (wire (pts (xy 36.195 235.585) (xy 38.735 235.585))
    (stroke (width 0) (type default))
  )
  (wire (pts (xy 214.63 277.495) (xy 214.63 257.175))
    (stroke (width 0) (type default))
  )
  (wire (pts (xy 277.495 70.485) (xy 300.355 70.485))
    (stroke (width 0) (type default))
  )
  (wire (pts (xy 35.56 255.27) (xy 38.1 255.27))
    (stroke (width 0) (type default))
  )
  (wire (pts (xy 204.47 77.47) (xy 210.82 77.47))
    (stroke (width 0) (type default))
  )
  (wire (pts (xy 121.285 93.98) (xy 131.445 93.98))
    (stroke (width 0) (type default))
  )
  (wire (pts (xy 259.08 245.11) (xy 267.335 245.11))
    (stroke (width 0) (type default))
  )
  (wire (pts (xy 224.155 167.64) (xy 224.155 177.165))
    (stroke (width 0) (type default))
  )
  (wire (pts (xy 236.22 85.09) (xy 243.84 85.09))
    (stroke (width 0) (type default))
  )
  (polyline (pts (xy 162.56 285.115) (xy 163.195 285.115))
    (stroke (width 0) (type default))
  )

  (wire (pts (xy 321.945 149.86) (xy 328.295 149.86))
    (stroke (width 0) (type default))
  )
  (wire (pts (xy 25.4 255.27) (xy 27.94 255.27))
    (stroke (width 0) (type default))
  )
  (wire (pts (xy 300.355 46.355) (xy 300.355 39.37))
    (stroke (width 0) (type default))
  )
  (wire (pts (xy 78.105 128.27) (xy 80.645 128.27))
    (stroke (width 0) (type default))
  )
  (wire (pts (xy 35.56 215.9) (xy 38.1 215.9))
    (stroke (width 0) (type default))
  )
  (wire (pts (xy 177.8 237.49) (xy 171.45 237.49))
    (stroke (width 0) (type default))
  )
  (wire (pts (xy 26.035 235.585) (xy 28.575 235.585))
    (stroke (width 0) (type default))
  )
  (wire (pts (xy 41.275 66.04) (xy 41.275 63.5))
    (stroke (width 0) (type default))
  )
  (wire (pts (xy 43.18 255.27) (xy 45.72 255.27))
    (stroke (width 0) (type default))
  )
  (wire (pts (xy 361.95 184.785) (xy 342.265 184.785))
    (stroke (width 0) (type default))
  )
  (wire (pts (xy 25.4 215.9) (xy 27.94 215.9))
    (stroke (width 0) (type default))
  )
  (wire (pts (xy 54.61 264.16) (xy 54.61 262.89))
    (stroke (width 0) (type default))
  )
  (wire (pts (xy 61.595 114.3) (xy 67.31 114.3))
    (stroke (width 0) (type default))
  )
  (wire (pts (xy 46.99 114.3) (xy 46.99 115.57))
    (stroke (width 0) (type default))
  )
  (wire (pts (xy 328.295 149.86) (xy 334.645 149.86))
    (stroke (width 0) (type default))
  )
  (wire (pts (xy 113.665 215.9) (xy 117.475 215.9))
    (stroke (width 0) (type default))
  )
  (wire (pts (xy 243.84 87.63) (xy 243.84 92.71))
    (stroke (width 0) (type default))
  )
  (wire (pts (xy 111.76 158.75) (xy 111.76 161.29))
    (stroke (width 0) (type default))
  )
  (wire (pts (xy 232.41 157.48) (xy 237.49 157.48))
    (stroke (width 0) (type default))
  )
  (wire (pts (xy 222.25 157.48) (xy 222.25 160.02))
    (stroke (width 0) (type default))
  )
  (wire (pts (xy 227.33 157.48) (xy 222.25 157.48))
    (stroke (width 0) (type default))
  )
  (wire (pts (xy 259.08 261.62) (xy 259.08 265.43))
    (stroke (width 0) (type default))
  )
  (wire (pts (xy 334.645 177.165) (xy 361.95 177.165))
    (stroke (width 0) (type default))
  )
  (wire (pts (xy 313.055 169.545) (xy 353.695 169.545))
    (stroke (width 0) (type default))
  )
  (wire (pts (xy 48.26 60.96) (xy 62.23 60.96))
    (stroke (width 0) (type default))
  )
  (wire (pts (xy 78.105 139.7) (xy 78.105 142.24))
    (stroke (width 0) (type default))
  )
  (wire (pts (xy 136.525 118.11) (xy 148.59 118.11))
    (stroke (width 0) (type default))
  )
  (wire (pts (xy 196.85 267.335) (xy 196.85 277.495))
    (stroke (width 0) (type default))
  )
  (wire (pts (xy 309.88 46.355) (xy 309.88 39.37))
    (stroke (width 0) (type default))
  )
  (wire (pts (xy 53.975 114.3) (xy 46.99 114.3))
    (stroke (width 0) (type default))
  )
  (wire (pts (xy 78.105 128.27) (xy 78.105 131.445))
    (stroke (width 0) (type default))
  )
  (wire (pts (xy 62.23 71.12) (xy 62.23 74.295))
    (stroke (width 0) (type default))
  )
  (wire (pts (xy 328.295 179.705) (xy 361.95 179.705))
    (stroke (width 0) (type default))
  )
  (wire (pts (xy 235.585 182.88) (xy 237.49 182.88))
    (stroke (width 0) (type default))
  )
  (wire (pts (xy 315.595 149.86) (xy 321.945 149.86))
    (stroke (width 0) (type default))
  )
  (wire (pts (xy 227.33 152.4) (xy 229.87 152.4))
    (stroke (width 0) (type default))
  )
  (wire (pts (xy 290.83 46.355) (xy 290.83 39.37))
    (stroke (width 0) (type default))
  )
  (polyline (pts (xy 128.27 212.725) (xy 299.72 212.725))
    (stroke (width 0) (type default))
  )

  (wire (pts (xy 313.055 172.085) (xy 347.345 172.085))
    (stroke (width 0) (type default))
  )
  (wire (pts (xy 321.945 182.245) (xy 361.95 182.245))
    (stroke (width 0) (type default))
  )
  (wire (pts (xy 214.63 244.475) (xy 214.63 243.205))
    (stroke (width 0) (type default))
  )
  (wire (pts (xy 267.335 255.905) (xy 267.335 261.62))
    (stroke (width 0) (type default))
  )
  (wire (pts (xy 338.455 60.325) (xy 338.455 51.435))
    (stroke (width 0) (type default))
  )
  (wire (pts (xy 48.26 71.12) (xy 48.26 74.295))
    (stroke (width 0) (type default))
  )
  (wire (pts (xy 328.295 160.02) (xy 328.295 179.705))
    (stroke (width 0) (type default))
  )
  (wire (pts (xy 68.58 158.75) (xy 68.58 161.29))
    (stroke (width 0) (type default))
  )
  (wire (pts (xy 384.175 99.06) (xy 387.35 99.06))
    (stroke (width 0) (type default))
  )
  (wire (pts (xy 22.86 60.96) (xy 26.035 60.96))
    (stroke (width 0) (type default))
  )
  (wire (pts (xy 177.8 238.125) (xy 177.8 237.49))
    (stroke (width 0) (type default))
  )
  (wire (pts (xy 290.83 51.435) (xy 290.83 73.025))
    (stroke (width 0) (type default))
  )
  (wire (pts (xy 319.405 46.355) (xy 319.405 39.37))
    (stroke (width 0) (type default))
  )
  (wire (pts (xy 136.525 93.98) (xy 148.59 93.98))
    (stroke (width 0) (type default))
  )
  (wire (pts (xy 131.445 72.39) (xy 121.285 72.39))
    (stroke (width 0) (type default))
  )
  (wire (pts (xy 277.495 60.325) (xy 338.455 60.325))
    (stroke (width 0) (type default))
  )
  (wire (pts (xy 168.91 253.365) (xy 207.01 253.365))
    (stroke (width 0) (type default))
  )
  (wire (pts (xy 375.92 67.31) (xy 379.095 67.31))
    (stroke (width 0) (type default))
  )
  (wire (pts (xy 60.96 158.75) (xy 56.515 158.75))
    (stroke (width 0) (type default))
  )
  (wire (pts (xy 41.275 63.5) (xy 55.245 63.5))
    (stroke (width 0) (type default))
  )
  (wire (pts (xy 259.08 245.11) (xy 259.08 246.38))
    (stroke (width 0) (type default))
  )
  (wire (pts (xy 229.87 152.4) (xy 237.49 152.4))
    (stroke (width 0) (type default))
  )
  (wire (pts (xy 78.74 66.04) (xy 78.74 57.15))
    (stroke (width 0) (type default))
  )
  (wire (pts (xy 48.26 66.04) (xy 48.26 60.96))
    (stroke (width 0) (type default))
  )
  (wire (pts (xy 321.945 154.94) (xy 321.945 149.86))
    (stroke (width 0) (type default))
  )
  (wire (pts (xy 338.455 60.325) (xy 338.455 80.645))
    (stroke (width 0) (type default))
  )
  (wire (pts (xy 347.345 172.085) (xy 361.95 172.085))
    (stroke (width 0) (type default))
  )
  (wire (pts (xy 338.455 46.355) (xy 338.455 39.37))
    (stroke (width 0) (type default))
  )
  (wire (pts (xy 404.495 193.04) (xy 404.495 191.135))
    (stroke (width 0) (type default))
  )
  (wire (pts (xy 313.055 182.245) (xy 321.945 182.245))
    (stroke (width 0) (type default))
  )
  (wire (pts (xy 136.525 115.57) (xy 148.59 115.57))
    (stroke (width 0) (type default))
  )
  (wire (pts (xy 281.305 51.435) (xy 281.305 75.565))
    (stroke (width 0) (type default))
  )
  (wire (pts (xy 210.82 57.15) (xy 203.2 57.15))
    (stroke (width 0) (type default))
  )
  (wire (pts (xy 77.47 87.63) (xy 80.645 87.63))
    (stroke (width 0) (type default))
  )
  (wire (pts (xy 204.47 62.23) (xy 210.82 62.23))
    (stroke (width 0) (type default))
  )
  (wire (pts (xy 171.45 229.87) (xy 214.63 229.87))
    (stroke (width 0) (type default))
  )
  (polyline (pts (xy 229.87 212.725) (xy 229.87 285.115))
    (stroke (width 0) (type default))
  )

  (wire (pts (xy 319.405 51.435) (xy 319.405 65.405))
    (stroke (width 0) (type default))
  )
  (wire (pts (xy 222.25 160.02) (xy 227.33 160.02))
    (stroke (width 0) (type default))
  )
  (wire (pts (xy 353.695 149.86) (xy 360.045 149.86))
    (stroke (width 0) (type default))
  )
  (wire (pts (xy 232.41 160.02) (xy 237.49 160.02))
    (stroke (width 0) (type default))
  )
  (wire (pts (xy 375.92 99.06) (xy 375.92 101.6))
    (stroke (width 0) (type default))
  )
  (wire (pts (xy 347.98 51.435) (xy 347.98 57.785))
    (stroke (width 0) (type default))
  )
  (wire (pts (xy 379.095 99.06) (xy 375.92 99.06))
    (stroke (width 0) (type default))
  )
  (wire (pts (xy 98.425 235.585) (xy 100.965 235.585))
    (stroke (width 0) (type default))
  )
  (wire (pts (xy 277.495 75.565) (xy 281.305 75.565))
    (stroke (width 0) (type default))
  )
  (wire (pts (xy 315.595 160.02) (xy 315.595 184.785))
    (stroke (width 0) (type default))
  )
  (wire (pts (xy 226.695 165.1) (xy 237.49 165.1))
    (stroke (width 0) (type default))
  )
  (wire (pts (xy 387.35 67.31) (xy 387.35 55.88))
    (stroke (width 0) (type default))
  )
  (wire (pts (xy 353.695 169.545) (xy 361.95 169.545))
    (stroke (width 0) (type default))
  )
  (wire (pts (xy 224.155 167.64) (xy 237.49 167.64))
    (stroke (width 0) (type default))
  )
  (wire (pts (xy 360.045 164.465) (xy 361.95 164.465))
    (stroke (width 0) (type default))
  )
  (wire (pts (xy 78.105 73.66) (xy 80.645 73.66))
    (stroke (width 0) (type default))
  )
  (wire (pts (xy 196.85 243.205) (xy 196.85 254.635))
    (stroke (width 0) (type default))
  )
  (wire (pts (xy 148.59 96.52) (xy 136.525 96.52))
    (stroke (width 0) (type default))
  )
  (wire (pts (xy 353.695 154.94) (xy 353.695 149.86))
    (stroke (width 0) (type default))
  )
  (wire (pts (xy 113.665 235.585) (xy 117.475 235.585))
    (stroke (width 0) (type default))
  )
  (wire (pts (xy 177.8 243.205) (xy 177.8 264.795))
    (stroke (width 0) (type default))
  )
  (wire (pts (xy 277.495 65.405) (xy 319.405 65.405))
    (stroke (width 0) (type default))
  )
  (wire (pts (xy 41.275 74.295) (xy 48.26 74.295))
    (stroke (width 0) (type default))
  )
  (wire (pts (xy 404.495 191.135) (xy 402.59 191.135))
    (stroke (width 0) (type default))
  )
  (wire (pts (xy 224.155 177.165) (xy 221.615 177.165))
    (stroke (width 0) (type default))
  )
  (wire (pts (xy 131.445 50.8) (xy 121.285 50.8))
    (stroke (width 0) (type default))
  )
  (wire (pts (xy 109.855 244.475) (xy 109.855 243.205))
    (stroke (width 0) (type default))
  )
  (wire (pts (xy 277.495 73.025) (xy 290.83 73.025))
    (stroke (width 0) (type default))
  )
  (wire (pts (xy 328.93 62.865) (xy 328.93 80.645))
    (stroke (width 0) (type default))
  )
  (wire (pts (xy 121.285 63.5) (xy 130.175 63.5))
    (stroke (width 0) (type default))
  )
  (wire (pts (xy 317.5 200.66) (xy 317.5 197.485))
    (stroke (width 0) (type default))
  )
  (wire (pts (xy 375.92 67.31) (xy 375.92 69.85))
    (stroke (width 0) (type default))
  )
  (wire (pts (xy 267.335 245.11) (xy 267.335 250.825))
    (stroke (width 0) (type default))
  )
  (wire (pts (xy 67.31 110.49) (xy 80.645 110.49))
    (stroke (width 0) (type default))
  )
  (wire (pts (xy 55.245 71.12) (xy 55.245 74.295))
    (stroke (width 0) (type default))
  )
  (wire (pts (xy 78.74 57.15) (xy 80.645 57.15))
    (stroke (width 0) (type default))
  )
  (wire (pts (xy 60.96 158.75) (xy 68.58 158.75))
    (stroke (width 0) (type default))
  )
  (wire (pts (xy 121.285 96.52) (xy 131.445 96.52))
    (stroke (width 0) (type default))
  )
  (wire (pts (xy 127 158.75) (xy 127 161.29))
    (stroke (width 0) (type default))
  )
  (wire (pts (xy 243.84 82.55) (xy 243.84 85.09))
    (stroke (width 0) (type default))
  )
  (wire (pts (xy 131.445 55.88) (xy 121.285 55.88))
    (stroke (width 0) (type default))
  )
  (wire (pts (xy 313.055 177.165) (xy 334.645 177.165))
    (stroke (width 0) (type default))
  )
  (wire (pts (xy 347.345 154.94) (xy 347.345 149.86))
    (stroke (width 0) (type default))
  )
  (wire (pts (xy 111.76 158.75) (xy 119.38 158.75))
    (stroke (width 0) (type default))
  )
  (polyline (pts (xy 359.41 12.7) (xy 359.41 120.65))
    (stroke (width 0) (type default))
  )

  (wire (pts (xy 277.495 62.865) (xy 328.93 62.865))
    (stroke (width 0) (type default))
  )
  (wire (pts (xy 340.995 174.625) (xy 361.95 174.625))
    (stroke (width 0) (type default))
  )
  (wire (pts (xy 222.885 184.785) (xy 222.885 182.245))
    (stroke (width 0) (type default))
  )
  (wire (pts (xy 26.035 63.5) (xy 28.575 63.5))
    (stroke (width 0) (type default))
  )
  (wire (pts (xy 136.525 53.34) (xy 148.59 53.34))
    (stroke (width 0) (type default))
  )
  (wire (pts (xy 328.295 154.94) (xy 328.295 149.86))
    (stroke (width 0) (type default))
  )
  (wire (pts (xy 313.055 179.705) (xy 328.295 179.705))
    (stroke (width 0) (type default))
  )
  (wire (pts (xy 136.525 74.93) (xy 148.59 74.93))
    (stroke (width 0) (type default))
  )
  (wire (pts (xy 98.425 215.9) (xy 100.965 215.9))
    (stroke (width 0) (type default))
  )
  (wire (pts (xy 313.055 184.785) (xy 315.595 184.785))
    (stroke (width 0) (type default))
  )
  (wire (pts (xy 384.175 67.31) (xy 387.35 67.31))
    (stroke (width 0) (type default))
  )
  (wire (pts (xy 48.26 74.295) (xy 55.245 74.295))
    (stroke (width 0) (type default))
  )
  (wire (pts (xy 204.47 72.39) (xy 210.82 72.39))
    (stroke (width 0) (type default))
  )
  (wire (pts (xy 277.495 67.945) (xy 309.88 67.945))
    (stroke (width 0) (type default))
  )
  (wire (pts (xy 340.995 160.02) (xy 340.995 174.625))
    (stroke (width 0) (type default))
  )
  (wire (pts (xy 334.645 154.94) (xy 334.645 149.86))
    (stroke (width 0) (type default))
  )
  (wire (pts (xy 69.85 57.15) (xy 78.74 57.15))
    (stroke (width 0) (type default))
  )
  (wire (pts (xy 72.39 87.63) (xy 69.85 87.63))
    (stroke (width 0) (type default))
  )
  (wire (pts (xy 204.47 90.17) (xy 210.82 90.17))
    (stroke (width 0) (type default))
  )
  (wire (pts (xy 78.105 76.2) (xy 80.645 76.2))
    (stroke (width 0) (type default))
  )
  (wire (pts (xy 196.85 233.68) (xy 196.85 238.125))
    (stroke (width 0) (type default))
  )
  (wire (pts (xy 334.645 149.86) (xy 340.995 149.86))
    (stroke (width 0) (type default))
  )
  (wire (pts (xy 236.22 77.47) (xy 243.84 77.47))
    (stroke (width 0) (type default))
  )
  (wire (pts (xy 54.61 224.79) (xy 54.61 223.52))
    (stroke (width 0) (type default))
  )
  (wire (pts (xy 67.31 110.49) (xy 67.31 114.3))
    (stroke (width 0) (type default))
  )
  (wire (pts (xy 259.08 256.54) (xy 259.08 261.62))
    (stroke (width 0) (type default))
  )
  (wire (pts (xy 136.525 72.39) (xy 148.59 72.39))
    (stroke (width 0) (type default))
  )
  (wire (pts (xy 328.93 51.435) (xy 328.93 62.865))
    (stroke (width 0) (type default))
  )
  (wire (pts (xy 80.645 66.04) (xy 78.74 66.04))
    (stroke (width 0) (type default))
  )
  (wire (pts (xy 226.695 179.705) (xy 221.615 179.705))
    (stroke (width 0) (type default))
  )
  (wire (pts (xy 281.305 75.565) (xy 281.305 80.645))
    (stroke (width 0) (type default))
  )
  (wire (pts (xy 210.82 41.91) (xy 203.2 41.91))
    (stroke (width 0) (type default))
  )
  (wire (pts (xy 236.22 82.55) (xy 243.84 82.55))
    (stroke (width 0) (type default))
  )
  (wire (pts (xy 78.105 136.525) (xy 78.105 139.7))
    (stroke (width 0) (type default))
  )
  (wire (pts (xy 55.245 63.5) (xy 80.645 63.5))
    (stroke (width 0) (type default))
  )
  (wire (pts (xy 243.84 80.01) (xy 243.84 82.55))
    (stroke (width 0) (type default))
  )
  (wire (pts (xy 109.855 224.79) (xy 109.855 223.52))
    (stroke (width 0) (type default))
  )
  (wire (pts (xy 361.315 191.135) (xy 361.95 191.135))
    (stroke (width 0) (type default))
  )
  (wire (pts (xy 319.405 65.405) (xy 319.405 80.645))
    (stroke (width 0) (type default))
  )
  (wire (pts (xy 33.655 63.5) (xy 41.275 63.5))
    (stroke (width 0) (type default))
  )
  (wire (pts (xy 90.805 235.585) (xy 93.345 235.585))
    (stroke (width 0) (type default))
  )
  (wire (pts (xy 131.445 74.93) (xy 121.285 74.93))
    (stroke (width 0) (type default))
  )
  (wire (pts (xy 387.35 101.6) (xy 387.35 99.06))
    (stroke (width 0) (type default))
  )
  (polyline (pts (xy 128.27 193.04) (xy 128.27 284.48))
    (stroke (width 0) (type default))
  )

  (wire (pts (xy 119.38 158.75) (xy 127 158.75))
    (stroke (width 0) (type default))
  )
  (wire (pts (xy 80.645 53.34) (xy 78.74 53.34))
    (stroke (width 0) (type default))
  )
  (wire (pts (xy 60.96 158.75) (xy 60.96 161.29))
    (stroke (width 0) (type default))
  )
  (wire (pts (xy 315.595 149.86) (xy 315.595 154.94))
    (stroke (width 0) (type default))
  )
  (wire (pts (xy 55.245 74.295) (xy 62.23 74.295))
    (stroke (width 0) (type default))
  )
  (wire (pts (xy 313.055 149.86) (xy 315.595 149.86))
    (stroke (width 0) (type default))
  )
  (wire (pts (xy 203.2 49.53) (xy 210.82 49.53))
    (stroke (width 0) (type default))
  )
  (wire (pts (xy 32.385 60.96) (xy 26.035 60.96))
    (stroke (width 0) (type default))
  )
  (wire (pts (xy 347.345 160.02) (xy 347.345 172.085))
    (stroke (width 0) (type default))
  )
  (wire (pts (xy 55.245 244.475) (xy 55.245 243.205))
    (stroke (width 0) (type default))
  )
  (wire (pts (xy 259.08 75.565) (xy 260.985 75.565))
    (stroke (width 0) (type default))
  )
  (wire (pts (xy 76.2 158.75) (xy 76.2 161.29))
    (stroke (width 0) (type default))
  )
  (wire (pts (xy 267.335 245.11) (xy 274.955 245.11))
    (stroke (width 0) (type default))
  )
  (wire (pts (xy 203.2 46.99) (xy 210.82 46.99))
    (stroke (width 0) (type default))
  )
  (wire (pts (xy 361.315 193.04) (xy 361.315 191.135))
    (stroke (width 0) (type default))
  )
  (wire (pts (xy 347.98 57.785) (xy 347.98 80.645))
    (stroke (width 0) (type default))
  )
  (wire (pts (xy 277.495 57.785) (xy 347.98 57.785))
    (stroke (width 0) (type default))
  )
  (wire (pts (xy 387.35 69.85) (xy 387.35 67.31))
    (stroke (width 0) (type default))
  )
  (wire (pts (xy 83.185 244.475) (xy 109.855 244.475))
    (stroke (width 0) (type default))
  )
  (wire (pts (xy 236.22 87.63) (xy 243.84 87.63))
    (stroke (width 0) (type default))
  )
  (wire (pts (xy 69.85 50.8) (xy 78.74 50.8))
    (stroke (width 0) (type default))
  )
  (wire (pts (xy 375.92 55.88) (xy 379.095 55.88))
    (stroke (width 0) (type default))
  )
  (wire (pts (xy 58.42 215.9) (xy 62.23 215.9))
    (stroke (width 0) (type default))
  )
  (wire (pts (xy 121.285 115.57) (xy 131.445 115.57))
    (stroke (width 0) (type default))
  )
  (wire (pts (xy 41.275 78.105) (xy 41.275 74.295))
    (stroke (width 0) (type default))
  )
  (wire (pts (xy 260.985 57.785) (xy 259.08 57.785))
    (stroke (width 0) (type default))
  )
  (wire (pts (xy 171.45 233.68) (xy 196.85 233.68))
    (stroke (width 0) (type default))
  )
  (wire (pts (xy 78.74 53.34) (xy 78.74 50.8))
    (stroke (width 0) (type default))
  )
  (wire (pts (xy 57.785 119.38) (xy 57.785 120.65))
    (stroke (width 0) (type default))
  )
  (wire (pts (xy 290.83 73.025) (xy 290.83 80.645))
    (stroke (width 0) (type default))
  )
  (wire (pts (xy 27.94 264.16) (xy 54.61 264.16))
    (stroke (width 0) (type default))
  )
  (wire (pts (xy 259.08 261.62) (xy 267.335 261.62))
    (stroke (width 0) (type default))
  )
  (wire (pts (xy 300.355 51.435) (xy 300.355 70.485))
    (stroke (width 0) (type default))
  )
  (wire (pts (xy 131.445 80.01) (xy 121.285 80.01))
    (stroke (width 0) (type default))
  )
  (polyline (pts (xy 12.065 193.04) (xy 127.635 193.04))
    (stroke (width 0) (type default))
  )

  (wire (pts (xy 375.92 67.31) (xy 375.92 55.88))
    (stroke (width 0) (type default))
  )
  (wire (pts (xy 334.645 160.02) (xy 334.645 177.165))
    (stroke (width 0) (type default))
  )
  (wire (pts (xy 211.455 165.1) (xy 226.695 165.1))
    (stroke (width 0) (type default))
  )
  (wire (pts (xy 80.645 215.9) (xy 83.185 215.9))
    (stroke (width 0) (type default))
  )
  (wire (pts (xy 121.285 118.11) (xy 131.445 118.11))
    (stroke (width 0) (type default))
  )
  (wire (pts (xy 168.91 273.685) (xy 170.18 273.685))
    (stroke (width 0) (type default))
  )
  (wire (pts (xy 222.885 182.245) (xy 221.615 182.245))
    (stroke (width 0) (type default))
  )
  (wire (pts (xy 315.595 184.785) (xy 337.185 184.785))
    (stroke (width 0) (type default))
  )
  (wire (pts (xy 107.315 158.75) (xy 111.76 158.75))
    (stroke (width 0) (type default))
  )
  (wire (pts (xy 340.995 149.86) (xy 347.345 149.86))
    (stroke (width 0) (type default))
  )
  (wire (pts (xy 210.82 39.37) (xy 203.2 39.37))
    (stroke (width 0) (type default))
  )
  (wire (pts (xy 43.18 215.9) (xy 45.72 215.9))
    (stroke (width 0) (type default))
  )
  (wire (pts (xy 78.105 142.24) (xy 78.105 144.145))
    (stroke (width 0) (type default))
  )
  (wire (pts (xy 226.695 165.1) (xy 226.695 179.705))
    (stroke (width 0) (type default))
  )
  (wire (pts (xy 90.805 215.9) (xy 93.345 215.9))
    (stroke (width 0) (type default))
  )
  (wire (pts (xy 80.645 235.585) (xy 83.185 235.585))
    (stroke (width 0) (type default))
  )
  (wire (pts (xy 256.54 256.54) (xy 256.54 261.62))
    (stroke (width 0) (type default))
  )
  (wire (pts (xy 211.455 167.64) (xy 224.155 167.64))
    (stroke (width 0) (type default))
  )
  (wire (pts (xy 204.47 82.55) (xy 210.82 82.55))
    (stroke (width 0) (type default))
  )
  (wire (pts (xy 210.82 54.61) (xy 203.2 54.61))
    (stroke (width 0) (type default))
  )
  (wire (pts (xy 136.525 50.8) (xy 148.59 50.8))
    (stroke (width 0) (type default))
  )
  (wire (pts (xy 230.505 180.34) (xy 237.49 180.34))
    (stroke (width 0) (type default))
  )
  (wire (pts (xy 227.33 147.955) (xy 229.87 147.955))
    (stroke (width 0) (type default))
  )
  (wire (pts (xy 243.84 85.09) (xy 243.84 87.63))
    (stroke (width 0) (type default))
  )
  (wire (pts (xy 313.055 174.625) (xy 340.995 174.625))
    (stroke (width 0) (type default))
  )
  (wire (pts (xy 214.63 229.87) (xy 214.63 238.125))
    (stroke (width 0) (type default))
  )
  (polyline (pts (xy 299.72 121.285) (xy 299.72 252.73))
    (stroke (width 0) (type default))
  )

  (wire (pts (xy 80.645 142.24) (xy 78.105 142.24))
    (stroke (width 0) (type default))
  )
  (wire (pts (xy 314.325 197.485) (xy 317.5 197.485))
    (stroke (width 0) (type default))
  )
  (wire (pts (xy 281.305 46.355) (xy 281.305 39.37))
    (stroke (width 0) (type default))
  )
  (wire (pts (xy 119.38 158.75) (xy 119.38 161.29))
    (stroke (width 0) (type default))
  )
  (wire (pts (xy 41.275 71.12) (xy 41.275 74.295))
    (stroke (width 0) (type default))
  )
  (wire (pts (xy 243.84 77.47) (xy 243.84 80.01))
    (stroke (width 0) (type default))
  )
  (wire (pts (xy 321.945 160.02) (xy 321.945 182.245))
    (stroke (width 0) (type default))
  )
  (wire (pts (xy 375.92 87.63) (xy 379.095 87.63))
    (stroke (width 0) (type default))
  )
  (wire (pts (xy 360.045 149.86) (xy 360.045 164.465))
    (stroke (width 0) (type default))
  )
  (wire (pts (xy 55.245 66.04) (xy 55.245 63.5))
    (stroke (width 0) (type default))
  )
  (wire (pts (xy 121.285 58.42) (xy 131.445 58.42))
    (stroke (width 0) (type default))
  )
  (wire (pts (xy 37.465 60.96) (xy 48.26 60.96))
    (stroke (width 0) (type default))
  )
  (wire (pts (xy 309.88 67.945) (xy 309.88 80.645))
    (stroke (width 0) (type default))
  )
  (polyline (pts (xy 178.435 120.65) (xy 408.305 120.65))
    (stroke (width 0) (type default))
  )

  (wire (pts (xy 230.505 184.785) (xy 230.505 180.34))
    (stroke (width 0) (type default))
  )
  (wire (pts (xy 43.815 235.585) (xy 46.355 235.585))
    (stroke (width 0) (type default))
  )
  (wire (pts (xy 168.91 263.525) (xy 189.23 263.525))
    (stroke (width 0) (type default))
  )
  (wire (pts (xy 131.445 85.09) (xy 121.285 85.09))
    (stroke (width 0) (type default))
  )

  (text "User LEDs" (at 16.51 200.66 0)
    (effects (font (size 2.9972 2.9972) (thickness 0.5994) bold) (justify left bottom))
  )
  (text "Debug UART" (at 14.605 20.955 0)
    (effects (font (size 2.9972 2.9972) (thickness 0.5994) bold) (justify left bottom))
  )
  (text "Debug USB" (at 179.705 127.635 0)
    (effects (font (size 2.9972 2.9972) (thickness 0.5994) bold) (justify left bottom))
  )
  (text "HOT SWAP eject button" (at 231.775 220.345 0)
    (effects (font (size 2.9972 2.9972) (thickness 0.5994) bold) (justify left bottom))
  )
  (text "Shield to GND" (at 361.95 19.05 0)
    (effects (font (size 2.9972 2.9972) (thickness 0.5994) bold) (justify left bottom))
  )
  (text "SD card" (at 302.895 128.905 0)
    (effects (font (size 2.9972 2.9972) (thickness 0.5994) bold) (justify left bottom))
  )
  (text "HOT SWAP status LED" (at 130.175 220.345 0)
    (effects (font (size 2.9972 2.9972) (thickness 0.5994) bold) (justify left bottom))
  )
  (text "HDMI" (at 179.07 18.415 0)
    (effects (font (size 2.9972 2.9972) (thickness 0.5994) bold) (justify left bottom))
  )
  (text "Optional RC filter, tr=10ms" (at 269.24 259.715 0)
    (effects (font (size 1.27 1.27)) (justify left bottom))
  )

  (global_label "C_TMDS_D1_P" (shape input) (at 203.2 46.99 180) (fields_autoplaced)
    (effects (font (size 1.27 1.27)) (justify right))
    (property "Intersheetrefs" "${INTERSHEET_REFS}" (at 476.885 -13.97 0)
      (effects (font (size 1.27 1.27)) hide)
    )
  )
  (global_label "3V3_SYS" (shape input) (at 69.85 87.63 180) (fields_autoplaced)
    (effects (font (size 1.27 1.27)) (justify right))
    (property "Intersheetrefs" "${INTERSHEET_REFS}" (at 1.905 -24.13 0)
      (effects (font (size 1.27 1.27)) hide)
    )
  )
  (global_label "1V8_FT" (shape input) (at 69.85 57.15 180) (fields_autoplaced)
    (effects (font (size 1.27 1.27)) (justify right))
    (property "Intersheetrefs" "${INTERSHEET_REFS}" (at 25.4 131.445 0)
      (effects (font (size 1.27 1.27)) hide)
    )
  )
  (global_label "TMDS_D0_N" (shape input) (at 300.355 39.37 90) (fields_autoplaced)
    (effects (font (size 1.27 1.27)) (justify left))
    (property "Intersheetrefs" "${INTERSHEET_REFS}" (at -46.355 -5.715 0)
      (effects (font (size 1.27 1.27)) hide)
    )
  )
  (global_label "3V3_SYS" (shape input) (at 69.85 50.8 180) (fields_autoplaced)
    (effects (font (size 1.27 1.27)) (justify right))
    (property "Intersheetrefs" "${INTERSHEET_REFS}" (at 25.4 128.905 0)
      (effects (font (size 1.27 1.27)) hide)
    )
  )
  (global_label "USR_LED5" (shape input) (at 83.185 244.475 180) (fields_autoplaced)
    (effects (font (size 1.27 1.27)) (justify right))
    (property "Intersheetrefs" "${INTERSHEET_REFS}" (at -123.19 -6.985 0)
      (effects (font (size 1.27 1.27)) hide)
    )
  )
  (global_label "AUX_JTAG_TMS" (shape input) (at 148.59 80.01 0) (fields_autoplaced)
    (effects (font (size 1.27 1.27)) (justify left))
    (property "Intersheetrefs" "${INTERSHEET_REFS}" (at 164.4071 80.01 0)
      (effects (font (size 1.27 1.27)) (justify left) hide)
    )
  )
  (global_label "VBUS" (shape input) (at 227.33 147.955 180) (fields_autoplaced)
    (effects (font (size 1.27 1.27)) (justify right))
    (property "Intersheetrefs" "${INTERSHEET_REFS}" (at 83.82 403.86 0)
      (effects (font (size 1.27 1.27)) hide)
    )
  )
  (global_label "UART0_TX" (shape input) (at 148.59 96.52 0) (fields_autoplaced)
    (effects (font (size 1.27 1.27)) (justify left))
    (property "Intersheetrefs" "${INTERSHEET_REFS}" (at 159.9319 96.52 0)
      (effects (font (size 1.27 1.27)) (justify left) hide)
    )
  )
  (global_label "AUX_JTAG_RST" (shape input) (at 148.59 85.09 0) (fields_autoplaced)
    (effects (font (size 1.27 1.27)) (justify left))
    (property "Intersheetrefs" "${INTERSHEET_REFS}" (at 164.2257 85.09 0)
      (effects (font (size 1.27 1.27)) (justify left) hide)
    )
  )
  (global_label "AUX_JTAG_TDO" (shape input) (at 148.59 77.47 0) (fields_autoplaced)
    (effects (font (size 1.27 1.27)) (justify left))
    (property "Intersheetrefs" "${INTERSHEET_REFS}" (at 164.3467 77.47 0)
      (effects (font (size 1.27 1.27)) (justify left) hide)
    )
  )
  (global_label "SD_CMD" (shape input) (at 313.055 174.625 180) (fields_autoplaced)
    (effects (font (size 1.27 1.27)) (justify right))
    (property "Intersheetrefs" "${INTERSHEET_REFS}" (at -2.54 -6.985 0)
      (effects (font (size 1.27 1.27)) hide)
    )
  )
  (global_label "C_TMDS_CLK_P" (shape input) (at 204.47 62.23 180) (fields_autoplaced)
    (effects (font (size 1.27 1.27)) (justify right))
    (property "Intersheetrefs" "${INTERSHEET_REFS}" (at 478.155 -6.35 0)
      (effects (font (size 1.27 1.27)) hide)
    )
  )
  (global_label "C_TMDS_D0_P" (shape input) (at 309.88 80.645 270) (fields_autoplaced)
    (effects (font (size 1.27 1.27)) (justify right))
    (property "Intersheetrefs" "${INTERSHEET_REFS}" (at -43.815 -12.7 0)
      (effects (font (size 1.27 1.27)) hide)
    )
  )
  (global_label "UART0_RX" (shape input) (at 148.59 93.98 0) (fields_autoplaced)
    (effects (font (size 1.27 1.27)) (justify left))
    (property "Intersheetrefs" "${INTERSHEET_REFS}" (at 160.2343 93.98 0)
      (effects (font (size 1.27 1.27)) (justify left) hide)
    )
  )
  (global_label "TMDS_CLK_N" (shape input) (at 281.305 39.37 90) (fields_autoplaced)
    (effects (font (size 1.27 1.27)) (justify left))
    (property "Intersheetrefs" "${INTERSHEET_REFS}" (at -51.435 -5.715 0)
      (effects (font (size 1.27 1.27)) hide)
    )
  )
  (global_label "SD_DAT0" (shape input) (at 313.055 179.705 180) (fields_autoplaced)
    (effects (font (size 1.27 1.27)) (justify right))
    (property "Intersheetrefs" "${INTERSHEET_REFS}" (at -2.54 -12.065 0)
      (effects (font (size 1.27 1.27)) hide)
    )
  )
  (global_label "C_TMDS_D1_P" (shape input) (at 328.93 80.645 270) (fields_autoplaced)
    (effects (font (size 1.27 1.27)) (justify right))
    (property "Intersheetrefs" "${INTERSHEET_REFS}" (at -38.735 -12.7 0)
      (effects (font (size 1.27 1.27)) hide)
    )
  )
  (global_label "TMDS_D2_N" (shape input) (at 338.455 39.37 90) (fields_autoplaced)
    (effects (font (size 1.27 1.27)) (justify left))
    (property "Intersheetrefs" "${INTERSHEET_REFS}" (at -36.195 -5.715 0)
      (effects (font (size 1.27 1.27)) hide)
    )
  )
  (global_label "3V3_SYS" (shape input) (at 80.645 235.585 180) (fields_autoplaced)
    (effects (font (size 1.27 1.27)) (justify right))
    (property "Intersheetrefs" "${INTERSHEET_REFS}" (at -123.19 -8.255 0)
      (effects (font (size 1.27 1.27)) hide)
    )
  )
  (global_label "C_TMDS_D0_P" (shape input) (at 203.2 54.61 180) (fields_autoplaced)
    (effects (font (size 1.27 1.27)) (justify right))
    (property "Intersheetrefs" "${INTERSHEET_REFS}" (at -34.29 -10.16 0)
      (effects (font (size 1.27 1.27)) hide)
    )
  )
  (global_label "TMDS_D1_P" (shape input) (at 328.93 38.735 90) (fields_autoplaced)
    (effects (font (size 1.27 1.27)) (justify left))
    (property "Intersheetrefs" "${INTERSHEET_REFS}" (at -38.735 -5.715 0)
      (effects (font (size 1.27 1.27)) hide)
    )
  )
  (global_label "SD_DAT2" (shape input) (at 313.055 169.545 180) (fields_autoplaced)
    (effects (font (size 1.27 1.27)) (justify right))
    (property "Intersheetrefs" "${INTERSHEET_REFS}" (at -2.54 -6.985 0)
      (effects (font (size 1.27 1.27)) hide)
    )
  )
  (global_label "3V3_SYS" (shape input) (at 22.86 60.96 180) (fields_autoplaced)
    (effects (font (size 1.27 1.27)) (justify right))
    (property "Intersheetrefs" "${INTERSHEET_REFS}" (at -54.61 84.455 0)
      (effects (font (size 1.27 1.27)) hide)
    )
  )
  (global_label "SD_DAT1" (shape input) (at 313.055 182.245 180) (fields_autoplaced)
    (effects (font (size 1.27 1.27)) (justify right))
    (property "Intersheetrefs" "${INTERSHEET_REFS}" (at -2.54 -12.065 0)
      (effects (font (size 1.27 1.27)) hide)
    )
  )
  (global_label "AUX_JTAG_TCK" (shape input) (at 148.59 72.39 0) (fields_autoplaced)
    (effects (font (size 1.27 1.27)) (justify left))
    (property "Intersheetrefs" "${INTERSHEET_REFS}" (at 164.2862 72.39 0)
      (effects (font (size 1.27 1.27)) (justify left) hide)
    )
  )
  (global_label "3V3_SYS" (shape input) (at 26.035 235.585 180) (fields_autoplaced)
    (effects (font (size 1.27 1.27)) (justify right))
    (property "Intersheetrefs" "${INTERSHEET_REFS}" (at -123.19 -8.255 0)
      (effects (font (size 1.27 1.27)) hide)
    )
  )
  (global_label "3V3_SYS" (shape input) (at 25.4 255.27 180) (fields_autoplaced)
    (effects (font (size 1.27 1.27)) (justify right))
    (property "Intersheetrefs" "${INTERSHEET_REFS}" (at -123.19 -8.255 0)
      (effects (font (size 1.27 1.27)) hide)
    )
  )
  (global_label "3V3_SYS" (shape input) (at 25.4 215.9 180) (fields_autoplaced)
    (effects (font (size 1.27 1.27)) (justify right))
    (property "Intersheetrefs" "${INTERSHEET_REFS}" (at -123.19 -8.255 0)
      (effects (font (size 1.27 1.27)) hide)
    )
  )
  (global_label "SD_CD" (shape input) (at 313.055 184.785 180) (fields_autoplaced)
    (effects (font (size 1.27 1.27)) (justify right))
    (property "Intersheetrefs" "${INTERSHEET_REFS}" (at -2.54 -12.065 0)
      (effects (font (size 1.27 1.27)) hide)
    )
  )
  (global_label "C_TMDS_CLK_P" (shape input) (at 290.83 80.645 270) (fields_autoplaced)
    (effects (font (size 1.27 1.27)) (justify right))
    (property "Intersheetrefs" "${INTERSHEET_REFS}" (at -48.895 -12.7 0)
      (effects (font (size 1.27 1.27)) hide)
    )
  )
  (global_label "C_TMDS_CLK_N" (shape input) (at 204.47 64.77 180) (fields_autoplaced)
    (effects (font (size 1.27 1.27)) (justify right))
    (property "Intersheetrefs" "${INTERSHEET_REFS}" (at 478.155 -6.35 0)
      (effects (font (size 1.27 1.27)) hide)
    )
  )
  (global_label "DBG_USB_N" (shape input) (at 78.105 76.2 180) (fields_autoplaced)
    (effects (font (size 1.27 1.27)) (justify right))
    (property "Intersheetrefs" "${INTERSHEET_REFS}" (at 4.445 172.72 0)
      (effects (font (size 1.27 1.27)) hide)
    )
  )
  (global_label "C_TMDS_D2_N" (shape input) (at 338.455 80.645 270) (fields_autoplaced)
    (effects (font (size 1.27 1.27)) (justify right))
    (property "Intersheetrefs" "${INTERSHEET_REFS}" (at -36.195 -12.7 0)
      (effects (font (size 1.27 1.27)) hide)
    )
  )
  (global_label "1V8_FT" (shape input) (at 107.315 158.75 180) (fields_autoplaced)
    (effects (font (size 1.27 1.27)) (justify right))
    (property "Intersheetrefs" "${INTERSHEET_REFS}" (at -60.96 304.165 0)
      (effects (font (size 1.27 1.27)) hide)
    )
  )
  (global_label "SD_CLK" (shape input) (at 313.055 177.165 180) (fields_autoplaced)
    (effects (font (size 1.27 1.27)) (justify right))
    (property "Intersheetrefs" "${INTERSHEET_REFS}" (at -2.54 -9.525 0)
      (effects (font (size 1.27 1.27)) hide)
    )
  )
  (global_label "3V3_SYS" (shape input) (at 80.645 215.9 180) (fields_autoplaced)
    (effects (font (size 1.27 1.27)) (justify right))
    (property "Intersheetrefs" "${INTERSHEET_REFS}" (at -123.19 -8.255 0)
      (effects (font (size 1.27 1.27)) hide)
    )
  )
  (global_label "C_TMDS_D2_P" (shape input) (at 203.2 39.37 180) (fields_autoplaced)
    (effects (font (size 1.27 1.27)) (justify right))
    (property "Intersheetrefs" "${INTERSHEET_REFS}" (at -34.29 -17.78 0)
      (effects (font (size 1.27 1.27)) hide)
    )
  )
  (global_label "SD_DAT3" (shape input) (at 313.055 172.085 180) (fields_autoplaced)
    (effects (font (size 1.27 1.27)) (justify right))
    (property "Intersheetrefs" "${INTERSHEET_REFS}" (at -2.54 -6.985 0)
      (effects (font (size 1.27 1.27)) hide)
    )
  )
  (global_label "TCK_JTAG" (shape input) (at 148.59 50.8 0) (fields_autoplaced)
    (effects (font (size 1.27 1.27)) (justify left))
    (property "Intersheetrefs" "${INTERSHEET_REFS}" (at 159.69 50.8 0)
      (effects (font (size 1.27 1.27)) (justify left) hide)
    )
  )
  (global_label "HOT_SWAP_YELLOW" (shape input) (at 168.91 273.685 180) (fields_autoplaced)
    (effects (font (size 1.27 1.27)) (justify right))
    (property "Intersheetrefs" "${INTERSHEET_REFS}" (at 148.9268 273.6056 0)
      (effects (font (size 1.27 1.27)) (justify right) hide)
    )
  )
  (global_label "C_TMDS_D1_N" (shape input) (at 319.405 80.645 270) (fields_autoplaced)
    (effects (font (size 1.27 1.27)) (justify right))
    (property "Intersheetrefs" "${INTERSHEET_REFS}" (at -41.275 -12.7 0)
      (effects (font (size 1.27 1.27)) hide)
    )
  )
  (global_label "HOT_SWAP_BUTTON" (shape input) (at 274.955 245.11 0) (fields_autoplaced)
    (effects (font (size 1.27 1.27)) (justify left))
    (property "Intersheetrefs" "${INTERSHEET_REFS}" (at 295.0592 245.0306 0)
      (effects (font (size 1.27 1.27)) (justify left) hide)
    )
  )
  (global_label "C_TMDS_CLK_N" (shape input) (at 281.305 80.645 270) (fields_autoplaced)
    (effects (font (size 1.27 1.27)) (justify right))
    (property "Intersheetrefs" "${INTERSHEET_REFS}" (at -51.435 -12.7 0)
      (effects (font (size 1.27 1.27)) hide)
    )
  )
  (global_label "UART1_RX" (shape input) (at 148.59 115.57 0) (fields_autoplaced)
    (effects (font (size 1.27 1.27)) (justify left))
    (property "Intersheetrefs" "${INTERSHEET_REFS}" (at 160.2343 115.57 0)
      (effects (font (size 1.27 1.27)) (justify left) hide)
    )
  )
  (global_label "USR_LED1" (shape input) (at 27.94 224.79 180) (fields_autoplaced)
    (effects (font (size 1.27 1.27)) (justify right))
    (property "Intersheetrefs" "${INTERSHEET_REFS}" (at -123.19 -6.985 0)
      (effects (font (size 1.27 1.27)) hide)
    )
  )
  (global_label "3V3_SYS" (shape input) (at 252.095 234.95 180) (fields_autoplaced)
    (effects (font (size 1.27 1.27)) (justify right))
    (property "Intersheetrefs" "${INTERSHEET_REFS}" (at 30.48 261.62 0)
      (effects (font (size 1.27 1.27)) hide)
    )
  )
  (global_label "DBG_USB_P" (shape input) (at 211.455 165.1 180) (fields_autoplaced)
    (effects (font (size 1.27 1.27)) (justify right))
    (property "Intersheetrefs" "${INTERSHEET_REFS}" (at -13.97 319.405 0)
      (effects (font (size 1.27 1.27)) hide)
    )
  )
  (global_label "TMDS_D1_N" (shape input) (at 319.405 39.37 90) (fields_autoplaced)
    (effects (font (size 1.27 1.27)) (justify left))
    (property "Intersheetrefs" "${INTERSHEET_REFS}" (at -41.275 -5.715 0)
      (effects (font (size 1.27 1.27)) hide)
    )
  )
  (global_label "C_TMDS_D0_N" (shape input) (at 203.2 57.15 180) (fields_autoplaced)
    (effects (font (size 1.27 1.27)) (justify right))
    (property "Intersheetrefs" "${INTERSHEET_REFS}" (at -34.29 -10.16 0)
      (effects (font (size 1.27 1.27)) hide)
    )
  )
  (global_label "USR_LED3" (shape input) (at 27.94 264.16 180) (fields_autoplaced)
    (effects (font (size 1.27 1.27)) (justify right))
    (property "Intersheetrefs" "${INTERSHEET_REFS}" (at -123.19 -6.985 0)
      (effects (font (size 1.27 1.27)) hide)
    )
  )
  (global_label "C_TMDS_D1_N" (shape input) (at 203.2 49.53 180) (fields_autoplaced)
    (effects (font (size 1.27 1.27)) (justify right))
    (property "Intersheetrefs" "${INTERSHEET_REFS}" (at 476.885 -13.97 0)
      (effects (font (size 1.27 1.27)) hide)
    )
  )
  (global_label "TMDS_D0_P" (shape input) (at 309.88 39.37 90) (fields_autoplaced)
    (effects (font (size 1.27 1.27)) (justify left))
    (property "Intersheetrefs" "${INTERSHEET_REFS}" (at -43.815 -5.715 0)
      (effects (font (size 1.27 1.27)) hide)
    )
  )
  (global_label "3V3_SYS" (shape input) (at 313.055 149.86 180) (fields_autoplaced)
    (effects (font (size 1.27 1.27)) (justify right))
    (property "Intersheetrefs" "${INTERSHEET_REFS}" (at 157.48 520.7 0)
      (effects (font (size 1.27 1.27)) hide)
    )
  )
  (global_label "TDO_JTAG" (shape input) (at 148.59 55.88 0) (fields_autoplaced)
    (effects (font (size 1.27 1.27)) (justify left))
    (property "Intersheetrefs" "${INTERSHEET_REFS}" (at 159.7505 55.88 0)
      (effects (font (size 1.27 1.27)) (justify left) hide)
    )
  )
  (global_label "3V3_SYS" (shape input) (at 259.08 57.785 180) (fields_autoplaced)
    (effects (font (size 1.27 1.27)) (justify right))
    (property "Intersheetrefs" "${INTERSHEET_REFS}" (at 205.74 363.855 0)
      (effects (font (size 1.27 1.27)) hide)
    )
  )
  (global_label "HOT_SWAP_GREEN" (shape input) (at 168.91 263.525 180) (fields_autoplaced)
    (effects (font (size 1.27 1.27)) (justify right))
    (property "Intersheetrefs" "${INTERSHEET_REFS}" (at 149.8339 263.4456 0)
      (effects (font (size 1.27 1.27)) (justify right) hide)
    )
  )
  (global_label "USR_LED4" (shape input) (at 83.185 224.79 180) (fields_autoplaced)
    (effects (font (size 1.27 1.27)) (justify right))
    (property "Intersheetrefs" "${INTERSHEET_REFS}" (at -123.19 -6.985 0)
      (effects (font (size 1.27 1.27)) hide)
    )
  )
  (global_label "C_TMDS_D2_N" (shape input) (at 203.2 41.91 180) (fields_autoplaced)
    (effects (font (size 1.27 1.27)) (justify right))
    (property "Intersheetrefs" "${INTERSHEET_REFS}" (at -34.29 -17.78 0)
      (effects (font (size 1.27 1.27)) hide)
    )
  )
  (global_label "C_TMDS_D0_N" (shape input) (at 300.355 80.645 270) (fields_autoplaced)
    (effects (font (size 1.27 1.27)) (justify right))
    (property "Intersheetrefs" "${INTERSHEET_REFS}" (at -46.355 -12.7 0)
      (effects (font (size 1.27 1.27)) hide)
    )
  )
  (global_label "C_TMDS_D2_P" (shape input) (at 347.98 80.645 270) (fields_autoplaced)
    (effects (font (size 1.27 1.27)) (justify right))
    (property "Intersheetrefs" "${INTERSHEET_REFS}" (at -33.655 -12.7 0)
      (effects (font (size 1.27 1.27)) hide)
    )
  )
  (global_label "USR_LED2" (shape input) (at 28.575 244.475 180) (fields_autoplaced)
    (effects (font (size 1.27 1.27)) (justify right))
    (property "Intersheetrefs" "${INTERSHEET_REFS}" (at -123.19 -6.985 0)
      (effects (font (size 1.27 1.27)) hide)
    )
  )
  (global_label "UART1_TX" (shape input) (at 148.59 118.11 0) (fields_autoplaced)
    (effects (font (size 1.27 1.27)) (justify left))
    (property "Intersheetrefs" "${INTERSHEET_REFS}" (at 159.9319 118.11 0)
      (effects (font (size 1.27 1.27)) (justify left) hide)
    )
  )
  (global_label "TMDS_D2_P" (shape input) (at 347.98 39.37 90) (fields_autoplaced)
    (effects (font (size 1.27 1.27)) (justify left))
    (property "Intersheetrefs" "${INTERSHEET_REFS}" (at -33.655 -5.715 0)
      (effects (font (size 1.27 1.27)) hide)
    )
  )
  (global_label "3V3_SYS" (shape input) (at 314.325 197.485 180) (fields_autoplaced)
    (effects (font (size 1.27 1.27)) (justify right))
    (property "Intersheetrefs" "${INTERSHEET_REFS}" (at 158.75 568.325 0)
      (effects (font (size 1.27 1.27)) hide)
    )
  )
  (global_label "3V3_SYS" (shape input) (at 56.515 158.75 180) (fields_autoplaced)
    (effects (font (size 1.27 1.27)) (justify right))
    (property "Intersheetrefs" "${INTERSHEET_REFS}" (at -83.185 304.165 0)
      (effects (font (size 1.27 1.27)) hide)
    )
  )
  (global_label "HOT_SWAP_RED" (shape input) (at 168.91 253.365 180) (fields_autoplaced)
    (effects (font (size 1.27 1.27)) (justify right))
    (property "Intersheetrefs" "${INTERSHEET_REFS}" (at 152.3134 253.2856 0)
      (effects (font (size 1.27 1.27)) (justify right) hide)
    )
  )
  (global_label "TDI_JTAG" (shape input) (at 148.59 53.34 0) (fields_autoplaced)
    (effects (font (size 1.27 1.27)) (justify left))
    (property "Intersheetrefs" "${INTERSHEET_REFS}" (at 159.0248 53.34 0)
      (effects (font (size 1.27 1.27)) (justify left) hide)
    )
  )
  (global_label "TMS_JTAG" (shape input) (at 148.59 58.42 0) (fields_autoplaced)
    (effects (font (size 1.27 1.27)) (justify left))
    (property "Intersheetrefs" "${INTERSHEET_REFS}" (at 159.8109 58.42 0)
      (effects (font (size 1.27 1.27)) (justify left) hide)
    )
  )
  (global_label "AUX_JTAG_TDI" (shape input) (at 148.59 74.93 0) (fields_autoplaced)
    (effects (font (size 1.27 1.27)) (justify left))
    (property "Intersheetrefs" "${INTERSHEET_REFS}" (at 163.621 74.93 0)
      (effects (font (size 1.27 1.27)) (justify left) hide)
    )
  )
  (global_label "DBG_USB_N" (shape input) (at 211.455 167.64 180) (fields_autoplaced)
    (effects (font (size 1.27 1.27)) (justify right))
    (property "Intersheetrefs" "${INTERSHEET_REFS}" (at -13.97 319.405 0)
      (effects (font (size 1.27 1.27)) hide)
    )
  )
  (global_label "DBG_USB_P" (shape input) (at 78.105 73.66 180) (fields_autoplaced)
    (effects (font (size 1.27 1.27)) (justify right))
    (property "Intersheetrefs" "${INTERSHEET_REFS}" (at 4.445 172.72 0)
      (effects (font (size 1.27 1.27)) hide)
    )
  )
  (global_label "TMDS_CLK_P" (shape input) (at 290.83 39.37 90) (fields_autoplaced)
    (effects (font (size 1.27 1.27)) (justify left))
    (property "Intersheetrefs" "${INTERSHEET_REFS}" (at -48.895 -5.715 0)
      (effects (font (size 1.27 1.27)) hide)
    )
  )
  (global_label "3V3_SYS" (shape input) (at 147.32 233.68 180) (fields_autoplaced)
    (effects (font (size 1.27 1.27)) (justify right))
    (property "Intersheetrefs" "${INTERSHEET_REFS}" (at -1.27 -29.845 0)
      (effects (font (size 1.27 1.27)) hide)
    )
  )

  (symbol (lib_id "antmicroResistors0402:R_22R_0402") (at 131.445 72.39 0) (unit 1)
    (in_bom yes) (on_board yes) (dnp no)
    (property "Reference" "R1" (at 130.175 71.12 0)
      (effects (font (size 1.524 1.524)))
    )
    (property "Value" "R_22R_0402" (at 151.765 85.09 0)
      (effects (font (size 1.27 1.27) (thickness 0.15)) (justify left bottom) hide)
    )
    (property "Footprint" "antmicro-footprints:R_0402_1005Metric" (at 151.765 87.63 0)
      (effects (font (size 1.27 1.27) (thickness 0.15)) (justify left bottom) hide)
    )
    (property "Datasheet" "https://www.bourns.com/docs/product-datasheets/cr.pdf" (at 151.765 90.17 0)
      (effects (font (size 1.27 1.27) (thickness 0.15)) (justify left bottom) hide)
    )
    (property "Manufacturer" "Bourns" (at 151.765 95.25 0)
      (effects (font (size 1.27 1.27) (thickness 0.15)) (justify left bottom) hide)
    )
    (property "MPN" "CR0402-FX-22R0GLF" (at 151.765 92.71 0)
      (effects (font (size 1.27 1.27) (thickness 0.15)) (justify left bottom) hide)
    )
    (property "Val" "22R" (at 138.43 71.12 0)
      (effects (font (size 1.27 1.27) (thickness 0.15)))
    )
    (property "License" "Apache-2.0" (at 151.765 97.79 0)
      (effects (font (size 1.27 1.27) (thickness 0.15)) (justify left bottom) hide)
    )
    (property "Author" "Antmicro" (at 151.765 100.33 0)
      (effects (font (size 1.27 1.27) (thickness 0.15)) (justify left bottom) hide)
    )
    (property "Tolerance" "1%" (at 151.765 82.55 0)
      (effects (font (size 1.27 1.27)) (justify left bottom) hide)
    )
    (pin "1")
    (pin "2")
    (instances
      (project "data-center-rdimm-ddr4-tester"
        (path ""
          (reference "R1") (unit 1)
        )
      )
    )
  )

  (symbol (lib_id "antmicroResistors0402:R_22R_0402") (at 131.445 74.93 0) (unit 1)
    (in_bom yes) (on_board yes) (dnp no)
    (property "Reference" "R2" (at 130.175 73.66 0)
      (effects (font (size 1.524 1.524)))
    )
    (property "Value" "R_22R_0402" (at 151.765 87.63 0)
      (effects (font (size 1.27 1.27) (thickness 0.15)) (justify left bottom) hide)
    )
    (property "Footprint" "antmicro-footprints:R_0402_1005Metric" (at 151.765 90.17 0)
      (effects (font (size 1.27 1.27) (thickness 0.15)) (justify left bottom) hide)
    )
    (property "Datasheet" "https://www.bourns.com/docs/product-datasheets/cr.pdf" (at 151.765 92.71 0)
      (effects (font (size 1.27 1.27) (thickness 0.15)) (justify left bottom) hide)
    )
    (property "Manufacturer" "Bourns" (at 151.765 97.79 0)
      (effects (font (size 1.27 1.27) (thickness 0.15)) (justify left bottom) hide)
    )
    (property "MPN" "CR0402-FX-22R0GLF" (at 151.765 95.25 0)
      (effects (font (size 1.27 1.27) (thickness 0.15)) (justify left bottom) hide)
    )
    (property "Val" "22R" (at 138.43 73.66 0)
      (effects (font (size 1.27 1.27) (thickness 0.15)))
    )
    (property "License" "Apache-2.0" (at 151.765 100.33 0)
      (effects (font (size 1.27 1.27) (thickness 0.15)) (justify left bottom) hide)
    )
    (property "Author" "Antmicro" (at 151.765 102.87 0)
      (effects (font (size 1.27 1.27) (thickness 0.15)) (justify left bottom) hide)
    )
    (property "Tolerance" "1%" (at 151.765 85.09 0)
      (effects (font (size 1.27 1.27)) (justify left bottom) hide)
    )
    (pin "1")
    (pin "2")
    (instances
      (project "data-center-rdimm-ddr4-tester"
        (path ""
          (reference "R2") (unit 1)
        )
      )
    )
  )

  (symbol (lib_id "antmicroResistors0402:R_22R_0402") (at 131.445 77.47 0) (unit 1)
    (in_bom yes) (on_board yes) (dnp no)
    (property "Reference" "R3" (at 130.175 76.2 0)
      (effects (font (size 1.524 1.524)))
    )
    (property "Value" "R_22R_0402" (at 151.765 90.17 0)
      (effects (font (size 1.27 1.27) (thickness 0.15)) (justify left bottom) hide)
    )
    (property "Footprint" "antmicro-footprints:R_0402_1005Metric" (at 151.765 92.71 0)
      (effects (font (size 1.27 1.27) (thickness 0.15)) (justify left bottom) hide)
    )
    (property "Datasheet" "https://www.bourns.com/docs/product-datasheets/cr.pdf" (at 151.765 95.25 0)
      (effects (font (size 1.27 1.27) (thickness 0.15)) (justify left bottom) hide)
    )
    (property "Manufacturer" "Bourns" (at 151.765 100.33 0)
      (effects (font (size 1.27 1.27) (thickness 0.15)) (justify left bottom) hide)
    )
    (property "MPN" "CR0402-FX-22R0GLF" (at 151.765 97.79 0)
      (effects (font (size 1.27 1.27) (thickness 0.15)) (justify left bottom) hide)
    )
    (property "Val" "22R" (at 138.43 76.2 0)
      (effects (font (size 1.27 1.27) (thickness 0.15)))
    )
    (property "License" "Apache-2.0" (at 151.765 102.87 0)
      (effects (font (size 1.27 1.27) (thickness 0.15)) (justify left bottom) hide)
    )
    (property "Author" "Antmicro" (at 151.765 105.41 0)
      (effects (font (size 1.27 1.27) (thickness 0.15)) (justify left bottom) hide)
    )
    (property "Tolerance" "1%" (at 151.765 87.63 0)
      (effects (font (size 1.27 1.27)) (justify left bottom) hide)
    )
    (pin "1")
    (pin "2")
    (instances
      (project "data-center-rdimm-ddr4-tester"
        (path ""
          (reference "R3") (unit 1)
        )
      )
    )
  )

  (symbol (lib_id "antmicroResistors0402:R_22R_0402") (at 131.445 80.01 0) (unit 1)
    (in_bom yes) (on_board yes) (dnp no)
    (property "Reference" "R4" (at 130.175 78.74 0)
      (effects (font (size 1.524 1.524)))
    )
    (property "Value" "R_22R_0402" (at 151.765 92.71 0)
      (effects (font (size 1.27 1.27) (thickness 0.15)) (justify left bottom) hide)
    )
    (property "Footprint" "antmicro-footprints:R_0402_1005Metric" (at 151.765 95.25 0)
      (effects (font (size 1.27 1.27) (thickness 0.15)) (justify left bottom) hide)
    )
    (property "Datasheet" "https://www.bourns.com/docs/product-datasheets/cr.pdf" (at 151.765 97.79 0)
      (effects (font (size 1.27 1.27) (thickness 0.15)) (justify left bottom) hide)
    )
    (property "Manufacturer" "Bourns" (at 151.765 102.87 0)
      (effects (font (size 1.27 1.27) (thickness 0.15)) (justify left bottom) hide)
    )
    (property "MPN" "CR0402-FX-22R0GLF" (at 151.765 100.33 0)
      (effects (font (size 1.27 1.27) (thickness 0.15)) (justify left bottom) hide)
    )
    (property "Val" "22R" (at 138.43 78.74 0)
      (effects (font (size 1.27 1.27) (thickness 0.15)))
    )
    (property "License" "Apache-2.0" (at 151.765 105.41 0)
      (effects (font (size 1.27 1.27) (thickness 0.15)) (justify left bottom) hide)
    )
    (property "Author" "Antmicro" (at 151.765 107.95 0)
      (effects (font (size 1.27 1.27) (thickness 0.15)) (justify left bottom) hide)
    )
    (property "Tolerance" "1%" (at 151.765 90.17 0)
      (effects (font (size 1.27 1.27)) (justify left bottom) hide)
    )
    (pin "1")
    (pin "2")
    (instances
      (project "data-center-rdimm-ddr4-tester"
        (path ""
          (reference "R4") (unit 1)
        )
      )
    )
  )

  (symbol (lib_id "antmicroResistors0402:R_22R_0402") (at 131.445 93.98 0) (unit 1)
    (in_bom yes) (on_board yes) (dnp no)
    (property "Reference" "R6" (at 130.175 92.71 0)
      (effects (font (size 1.524 1.524)))
    )
    (property "Value" "R_22R_0402" (at 151.765 106.68 0)
      (effects (font (size 1.27 1.27) (thickness 0.15)) (justify left bottom) hide)
    )
    (property "Footprint" "antmicro-footprints:R_0402_1005Metric" (at 151.765 109.22 0)
      (effects (font (size 1.27 1.27) (thickness 0.15)) (justify left bottom) hide)
    )
    (property "Datasheet" "https://www.bourns.com/docs/product-datasheets/cr.pdf" (at 151.765 111.76 0)
      (effects (font (size 1.27 1.27) (thickness 0.15)) (justify left bottom) hide)
    )
    (property "Manufacturer" "Bourns" (at 151.765 116.84 0)
      (effects (font (size 1.27 1.27) (thickness 0.15)) (justify left bottom) hide)
    )
    (property "MPN" "CR0402-FX-22R0GLF" (at 151.765 114.3 0)
      (effects (font (size 1.27 1.27) (thickness 0.15)) (justify left bottom) hide)
    )
    (property "Val" "22R" (at 138.43 92.71 0)
      (effects (font (size 1.27 1.27) (thickness 0.15)))
    )
    (property "License" "Apache-2.0" (at 151.765 119.38 0)
      (effects (font (size 1.27 1.27) (thickness 0.15)) (justify left bottom) hide)
    )
    (property "Author" "Antmicro" (at 151.765 121.92 0)
      (effects (font (size 1.27 1.27) (thickness 0.15)) (justify left bottom) hide)
    )
    (property "Tolerance" "1%" (at 151.765 104.14 0)
      (effects (font (size 1.27 1.27)) (justify left bottom) hide)
    )
    (pin "1")
    (pin "2")
    (instances
      (project "data-center-rdimm-ddr4-tester"
        (path ""
          (reference "R6") (unit 1)
        )
      )
    )
  )

  (symbol (lib_id "antmicroResistors0402:R_22R_0402") (at 131.445 118.11 0) (unit 1)
    (in_bom yes) (on_board yes) (dnp no)
    (property "Reference" "R37" (at 129.54 116.84 0)
      (effects (font (size 1.524 1.524)))
    )
    (property "Value" "R_22R_0402" (at 151.765 130.81 0)
      (effects (font (size 1.27 1.27) (thickness 0.15)) (justify left bottom) hide)
    )
    (property "Footprint" "antmicro-footprints:R_0402_1005Metric" (at 151.765 133.35 0)
      (effects (font (size 1.27 1.27) (thickness 0.15)) (justify left bottom) hide)
    )
    (property "Datasheet" "https://www.bourns.com/docs/product-datasheets/cr.pdf" (at 151.765 135.89 0)
      (effects (font (size 1.27 1.27) (thickness 0.15)) (justify left bottom) hide)
    )
    (property "Manufacturer" "Bourns" (at 151.765 140.97 0)
      (effects (font (size 1.27 1.27) (thickness 0.15)) (justify left bottom) hide)
    )
    (property "MPN" "CR0402-FX-22R0GLF" (at 151.765 138.43 0)
      (effects (font (size 1.27 1.27) (thickness 0.15)) (justify left bottom) hide)
    )
    (property "Val" "22R" (at 138.43 116.84 0)
      (effects (font (size 1.27 1.27) (thickness 0.15)))
    )
    (property "License" "Apache-2.0" (at 151.765 143.51 0)
      (effects (font (size 1.27 1.27) (thickness 0.15)) (justify left bottom) hide)
    )
    (property "Author" "Antmicro" (at 151.765 146.05 0)
      (effects (font (size 1.27 1.27) (thickness 0.15)) (justify left bottom) hide)
    )
    (property "Tolerance" "1%" (at 151.765 128.27 0)
      (effects (font (size 1.27 1.27)) (justify left bottom) hide)
    )
    (pin "1")
    (pin "2")
    (instances
      (project "data-center-rdimm-ddr4-tester"
        (path ""
          (reference "R37") (unit 1)
        )
      )
    )
  )

  (symbol (lib_id "antmicroResistors0402:R_22R_0402") (at 131.445 96.52 0) (unit 1)
    (in_bom yes) (on_board yes) (dnp no)
    (property "Reference" "R7" (at 130.175 95.25 0)
      (effects (font (size 1.524 1.524)))
    )
    (property "Value" "R_22R_0402" (at 151.765 109.22 0)
      (effects (font (size 1.27 1.27) (thickness 0.15)) (justify left bottom) hide)
    )
    (property "Footprint" "antmicro-footprints:R_0402_1005Metric" (at 151.765 111.76 0)
      (effects (font (size 1.27 1.27) (thickness 0.15)) (justify left bottom) hide)
    )
    (property "Datasheet" "https://www.bourns.com/docs/product-datasheets/cr.pdf" (at 151.765 114.3 0)
      (effects (font (size 1.27 1.27) (thickness 0.15)) (justify left bottom) hide)
    )
    (property "Manufacturer" "Bourns" (at 151.765 119.38 0)
      (effects (font (size 1.27 1.27) (thickness 0.15)) (justify left bottom) hide)
    )
    (property "MPN" "CR0402-FX-22R0GLF" (at 151.765 116.84 0)
      (effects (font (size 1.27 1.27) (thickness 0.15)) (justify left bottom) hide)
    )
    (property "Val" "22R" (at 138.43 95.25 0)
      (effects (font (size 1.27 1.27) (thickness 0.15)))
    )
    (property "License" "Apache-2.0" (at 151.765 121.92 0)
      (effects (font (size 1.27 1.27) (thickness 0.15)) (justify left bottom) hide)
    )
    (property "Author" "Antmicro" (at 151.765 124.46 0)
      (effects (font (size 1.27 1.27) (thickness 0.15)) (justify left bottom) hide)
    )
    (property "Tolerance" "1%" (at 151.765 106.68 0)
      (effects (font (size 1.27 1.27)) (justify left bottom) hide)
    )
    (pin "1")
    (pin "2")
    (instances
      (project "data-center-rdimm-ddr4-tester"
        (path ""
          (reference "R7") (unit 1)
        )
      )
    )
  )

  (symbol (lib_id "antmicroResistors0402:R_22R_0402") (at 131.445 115.57 0) (unit 1)
    (in_bom yes) (on_board yes) (dnp no)
    (property "Reference" "R8" (at 129.54 114.3 0)
      (effects (font (size 1.524 1.524)))
    )
    (property "Value" "R_22R_0402" (at 151.765 128.27 0)
      (effects (font (size 1.27 1.27) (thickness 0.15)) (justify left bottom) hide)
    )
    (property "Footprint" "antmicro-footprints:R_0402_1005Metric" (at 151.765 130.81 0)
      (effects (font (size 1.27 1.27) (thickness 0.15)) (justify left bottom) hide)
    )
    (property "Datasheet" "https://www.bourns.com/docs/product-datasheets/cr.pdf" (at 151.765 133.35 0)
      (effects (font (size 1.27 1.27) (thickness 0.15)) (justify left bottom) hide)
    )
    (property "Manufacturer" "Bourns" (at 151.765 138.43 0)
      (effects (font (size 1.27 1.27) (thickness 0.15)) (justify left bottom) hide)
    )
    (property "MPN" "CR0402-FX-22R0GLF" (at 151.765 135.89 0)
      (effects (font (size 1.27 1.27) (thickness 0.15)) (justify left bottom) hide)
    )
    (property "Val" "22R" (at 138.43 114.3 0)
      (effects (font (size 1.27 1.27) (thickness 0.15)))
    )
    (property "License" "Apache-2.0" (at 151.765 140.97 0)
      (effects (font (size 1.27 1.27) (thickness 0.15)) (justify left bottom) hide)
    )
    (property "Author" "Antmicro" (at 151.765 143.51 0)
      (effects (font (size 1.27 1.27) (thickness 0.15)) (justify left bottom) hide)
    )
    (property "Tolerance" "1%" (at 151.765 125.73 0)
      (effects (font (size 1.27 1.27)) (justify left bottom) hide)
    )
    (pin "1")
    (pin "2")
    (instances
      (project "data-center-rdimm-ddr4-tester"
        (path ""
          (reference "R8") (unit 1)
        )
      )
    )
  )

  (symbol (lib_id "antmicropower:GND") (at 62.23 215.9 90) (unit 1)
    (in_bom yes) (on_board yes) (dnp no) (fields_autoplaced)
    (property "Reference" "#PWR0167" (at 68.58 215.9 0)
      (effects (font (size 1.27 1.27)) hide)
    )
    (property "Value" "GND" (at 66.04 215.8999 90)
      (effects (font (size 1.27 1.27)) (justify right))
    )
    (property "Footprint" "" (at 62.23 215.9 0)
      (effects (font (size 1.27 1.27)) hide)
    )
    (property "Datasheet" "" (at 62.23 215.9 0)
      (effects (font (size 1.27 1.27)) hide)
    )
    (property "Author" "Antmicro" (at 69.85 207.01 0)
      (effects (font (size 1.27 1.27) (thickness 0.15)) (justify left bottom) hide)
    )
    (property "License" "Apache-2.0" (at 72.39 207.01 0)
      (effects (font (size 1.27 1.27) (thickness 0.15)) (justify left bottom) hide)
    )
    (pin "1")
    (instances
      (project "data-center-rdimm-ddr4-tester"
        (path ""
          (reference "#PWR0167") (unit 1)
        )
      )
    )
  )

  (symbol (lib_id "antmicroResistors0402:R_330R_0402") (at 38.1 215.9 0) (unit 1)
    (in_bom yes) (on_board yes) (dnp no)
    (property "Reference" "R50" (at 40.64 219.075 0)
      (effects (font (size 1.524 1.524)))
    )
    (property "Value" "R_330R_0402" (at 58.42 228.6 0)
      (effects (font (size 1.27 1.27) (thickness 0.15)) (justify left bottom) hide)
    )
    (property "Footprint" "antmicro-footprints:R_0402_1005Metric" (at 58.42 231.14 0)
      (effects (font (size 1.27 1.27) (thickness 0.15)) (justify left bottom) hide)
    )
    (property "Datasheet" "https://www.bourns.com/docs/product-datasheets/cr.pdf" (at 58.42 233.68 0)
      (effects (font (size 1.27 1.27) (thickness 0.15)) (justify left bottom) hide)
    )
    (property "Manufacturer" "Bourns" (at 58.42 238.76 0)
      (effects (font (size 1.27 1.27) (thickness 0.15)) (justify left bottom) hide)
    )
    (property "MPN" "CR0402-FX-3300GLF" (at 58.42 236.22 0)
      (effects (font (size 1.27 1.27) (thickness 0.15)) (justify left bottom) hide)
    )
    (property "Val" "330R" (at 40.64 221.615 0)
      (effects (font (size 1.27 1.27) (thickness 0.15)))
    )
    (property "License" "Apache-2.0" (at 58.42 241.3 0)
      (effects (font (size 1.27 1.27) (thickness 0.15)) (justify left bottom) hide)
    )
    (property "Author" "Antmicro" (at 58.42 243.84 0)
      (effects (font (size 1.27 1.27) (thickness 0.15)) (justify left bottom) hide)
    )
    (property "Tolerance" "1%" (at 58.42 226.06 0)
      (effects (font (size 1.27 1.27)) (justify left bottom) hide)
    )
    (pin "1")
    (pin "2")
    (instances
      (project "data-center-rdimm-ddr4-tester"
        (path ""
          (reference "R50") (unit 1)
        )
      )
    )
  )

  (symbol (lib_id "antmicroLEDIndicationDiscrete:LED_G_0603_KP-1608CGCK") (at 27.94 215.9 0) (unit 1)
    (in_bom yes) (on_board yes) (dnp no) (fields_autoplaced)
    (property "Reference" "D5" (at 31.75 208.28 0)
      (effects (font (size 1.524 1.524)))
    )
    (property "Value" "LED_G_0603_KP-1608CGCK" (at 31.75 210.82 0)
      (effects (font (size 1.27 1.27) (thickness 0.15)) hide)
    )
    (property "Footprint" "antmicro-footprints:LED_0603_1608Metric_G" (at 50.8 226.06 0)
      (effects (font (size 1.27 1.27) (thickness 0.15)) (justify left bottom) hide)
    )
    (property "Datasheet" "http://www.farnell.com/datasheets/2045956.pdf" (at 50.8 228.6 0)
      (effects (font (size 1.27 1.27) (thickness 0.15)) (justify left bottom) hide)
    )
    (property "MPN" "KP-1608CGCK" (at 31.75 210.82 0)
      (effects (font (size 1.27 1.27) (thickness 0.15)))
    )
    (property "Manufacturer" "Kingbright" (at 50.8 233.68 0)
      (effects (font (size 1.27 1.27) (thickness 0.15)) (justify left bottom) hide)
    )
    (property "Author" "Antmicro" (at 50.8 236.22 0)
      (effects (font (size 1.27 1.27) (thickness 0.15)) (justify left bottom) hide)
    )
    (property "License" "Apache-2.0" (at 50.8 238.76 0)
      (effects (font (size 1.27 1.27) (thickness 0.15)) (justify left bottom) hide)
    )
    (pin "1")
    (pin "2")
    (instances
      (project "data-center-rdimm-ddr4-tester"
        (path ""
          (reference "D5") (unit 1)
        )
      )
    )
  )

  (symbol (lib_id "data-center-rdimm-ddr4-tester:FB_600Z_0.5A_0603") (at 32.385 60.96 0) (unit 1)
    (in_bom yes) (on_board yes) (dnp no)
    (property "Reference" "FB5" (at 35.56 55.245 0)
      (effects (font (size 1.524 1.524)))
    )
    (property "Value" "FB_600Z_0.5A_0603" (at 47.625 66.04 0)
      (effects (font (size 1.27 1.27) (thickness 0.15)) (justify left bottom) hide)
    )
    (property "Footprint" "data-center-rdimm-ddr4-tester-footprints:FB_0603_1608Metric" (at 47.625 68.58 0)
      (effects (font (size 1.27 1.27) (thickness 0.15)) (justify left bottom) hide)
    )
    (property "Datasheet" "https://www.murata.com/en-us/products/productdata/8796738650142/ENFA0003.pdf" (at 47.625 71.12 0)
      (effects (font (size 1.27 1.27) (thickness 0.15)) (justify left bottom) hide)
    )
    (property "MPN" "BLM18AG601SN1D" (at 35.56 57.785 0)
      (effects (font (size 1.27 1.27) (thickness 0.15)))
    )
    (property "Manufacturer" "Murata" (at 47.625 76.2 0)
      (effects (font (size 1.27 1.27) (thickness 0.15)) (justify left bottom) hide)
    )
    (property "Author" "Antmicro" (at 47.625 78.74 0)
      (effects (font (size 1.27 1.27) (thickness 0.15)) (justify left bottom) hide)
    )
    (property "License" "Apache-2.0" (at 47.625 81.28 0)
      (effects (font (size 1.27 1.27) (thickness 0.15)) (justify left bottom) hide)
    )
    (pin "1")
    (pin "2")
    (instances
      (project "data-center-rdimm-ddr4-tester"
        (path ""
          (reference "FB5") (unit 1)
        )
      )
    )
  )

  (symbol (lib_id "data-center-rdimm-ddr4-tester:FB_600Z_0.5A_0603") (at 28.575 63.5 0) (unit 1)
    (in_bom yes) (on_board yes) (dnp no)
    (property "Reference" "FB4" (at 31.0769 67.945 0)
      (effects (font (size 1.524 1.524)))
    )
    (property "Value" "FB_600Z_0.5A_0603" (at 43.815 68.58 0)
      (effects (font (size 1.27 1.27) (thickness 0.15)) (justify left bottom) hide)
    )
    (property "Footprint" "data-center-rdimm-ddr4-tester-footprints:FB_0603_1608Metric" (at 43.815 71.12 0)
      (effects (font (size 1.27 1.27) (thickness 0.15)) (justify left bottom) hide)
    )
    (property "Datasheet" "https://www.murata.com/en-us/products/productdata/8796738650142/ENFA0003.pdf" (at 43.815 73.66 0)
      (effects (font (size 1.27 1.27) (thickness 0.15)) (justify left bottom) hide)
    )
    (property "MPN" "BLM18AG601SN1D" (at 31.115 70.485 0)
      (effects (font (size 1.27 1.27) (thickness 0.15)))
    )
    (property "Manufacturer" "Murata" (at 43.815 78.74 0)
      (effects (font (size 1.27 1.27) (thickness 0.15)) (justify left bottom) hide)
    )
    (property "Author" "Antmicro" (at 43.815 81.28 0)
      (effects (font (size 1.27 1.27) (thickness 0.15)) (justify left bottom) hide)
    )
    (property "License" "Apache-2.0" (at 43.815 83.82 0)
      (effects (font (size 1.27 1.27) (thickness 0.15)) (justify left bottom) hide)
    )
    (pin "1")
    (pin "2")
    (instances
      (project "data-center-rdimm-ddr4-tester"
        (path ""
          (reference "FB4") (unit 1)
        )
      )
    )
  )

  (symbol (lib_id "antmicroCapacitors0402:C_100n_0402") (at 48.26 66.04 270) (unit 1)
    (in_bom yes) (on_board yes) (dnp no)
    (property "Reference" "C185" (at 48.895 66.675 90)
      (effects (font (size 1.524 1.524)) (justify left))
    )
    (property "Value" "C_100n_0402" (at 38.1 86.36 0)
      (effects (font (size 1.27 1.27) (thickness 0.15)) (justify left bottom) hide)
    )
    (property "Footprint" "antmicro-footprints:C_0402_1005Metric" (at 35.56 86.36 0)
      (effects (font (size 1.27 1.27) (thickness 0.15)) (justify left bottom) hide)
    )
    (property "Datasheet" "https://search.murata.co.jp/Ceramy/image/img/A01X/G101/ENG/GRM155R61H104KE14-01.pdf" (at 33.02 86.36 0)
      (effects (font (size 1.27 1.27) (thickness 0.15)) (justify left bottom) hide)
    )
    (property "Manufacturer" "Murata" (at 27.94 86.36 0)
      (effects (font (size 1.27 1.27) (thickness 0.15)) (justify left bottom) hide)
    )
    (property "MPN" "GRM155R61H104KE14D" (at 30.48 86.36 0)
      (effects (font (size 1.27 1.27) (thickness 0.15)) (justify left bottom) hide)
    )
    (property "Val" "100n" (at 48.895 70.485 90)
      (effects (font (size 1.27 1.27) (thickness 0.15)) (justify left))
    )
    (property "License" "Apache-2.0" (at 25.4 86.36 0)
      (effects (font (size 1.27 1.27) (thickness 0.15)) (justify left bottom) hide)
    )
    (property "Author" "Antmicro" (at 22.86 86.36 0)
      (effects (font (size 1.27 1.27) (thickness 0.15)) (justify left bottom) hide)
    )
    (property "Voltage" "50V" (at 20.32 86.36 0)
      (effects (font (size 1.27 1.27)) (justify left bottom) hide)
    )
    (property "Dielectric" "X5R" (at 17.78 86.36 0)
      (effects (font (size 1.27 1.27)) (justify left bottom) hide)
    )
    (pin "1")
    (pin "2")
    (instances
      (project "data-center-rdimm-ddr4-tester"
        (path ""
          (reference "C185") (unit 1)
        )
      )
    )
  )

  (symbol (lib_id "antmicroCapacitors0402:C_4u7_0402") (at 62.23 66.04 270) (unit 1)
    (in_bom yes) (on_board yes) (dnp no)
    (property "Reference" "C189" (at 62.865 66.675 90)
      (effects (font (size 1.524 1.524)) (justify left))
    )
    (property "Value" "C_4u7_0402" (at 52.07 86.36 0)
      (effects (font (size 1.27 1.27) (thickness 0.15)) (justify left bottom) hide)
    )
    (property "Footprint" "antmicro-footprints:C_0402_1005Metric" (at 49.53 86.36 0)
      (effects (font (size 1.27 1.27) (thickness 0.15)) (justify left bottom) hide)
    )
    (property "Datasheet" " " (at 46.99 86.36 0)
      (effects (font (size 1.27 1.27) (thickness 0.15)) (justify left bottom) hide)
    )
    (property "Manufacturer" "Murata" (at 41.91 86.36 0)
      (effects (font (size 1.27 1.27) (thickness 0.15)) (justify left bottom) hide)
    )
    (property "MPN" "GRM155R61A475MEAAD" (at 44.45 86.36 0)
      (effects (font (size 1.27 1.27) (thickness 0.15)) (justify left bottom) hide)
    )
    (property "Val" "4u7" (at 62.865 70.485 90)
      (effects (font (size 1.27 1.27) (thickness 0.15)) (justify left))
    )
    (property "License" "Apache-2.0" (at 39.37 86.36 0)
      (effects (font (size 1.27 1.27) (thickness 0.15)) (justify left bottom) hide)
    )
    (property "Author" "Antmicro" (at 36.83 86.36 0)
      (effects (font (size 1.27 1.27) (thickness 0.15)) (justify left bottom) hide)
    )
    (property "Voltage" "" (at 34.29 86.36 0)
      (effects (font (size 1.27 1.27)) (justify left bottom) hide)
    )
    (property "Dielectric" "" (at 31.75 86.36 0)
      (effects (font (size 1.27 1.27)) (justify left bottom) hide)
    )
    (pin "1")
    (pin "2")
    (instances
      (project "data-center-rdimm-ddr4-tester"
        (path ""
          (reference "C189") (unit 1)
        )
      )
    )
  )

  (symbol (lib_id "antmicroCapacitors0402:C_100n_0402") (at 41.275 66.04 270) (unit 1)
    (in_bom yes) (on_board yes) (dnp no)
    (property "Reference" "C184" (at 41.91 66.675 90)
      (effects (font (size 1.524 1.524)) (justify left))
    )
    (property "Value" "C_100n_0402" (at 31.115 86.36 0)
      (effects (font (size 1.27 1.27) (thickness 0.15)) (justify left bottom) hide)
    )
    (property "Footprint" "antmicro-footprints:C_0402_1005Metric" (at 28.575 86.36 0)
      (effects (font (size 1.27 1.27) (thickness 0.15)) (justify left bottom) hide)
    )
    (property "Datasheet" "https://search.murata.co.jp/Ceramy/image/img/A01X/G101/ENG/GRM155R61H104KE14-01.pdf" (at 26.035 86.36 0)
      (effects (font (size 1.27 1.27) (thickness 0.15)) (justify left bottom) hide)
    )
    (property "Manufacturer" "Murata" (at 20.955 86.36 0)
      (effects (font (size 1.27 1.27) (thickness 0.15)) (justify left bottom) hide)
    )
    (property "MPN" "GRM155R61H104KE14D" (at 23.495 86.36 0)
      (effects (font (size 1.27 1.27) (thickness 0.15)) (justify left bottom) hide)
    )
    (property "Val" "100n" (at 41.91 70.485 90)
      (effects (font (size 1.27 1.27) (thickness 0.15)) (justify left))
    )
    (property "License" "Apache-2.0" (at 18.415 86.36 0)
      (effects (font (size 1.27 1.27) (thickness 0.15)) (justify left bottom) hide)
    )
    (property "Author" "Antmicro" (at 15.875 86.36 0)
      (effects (font (size 1.27 1.27) (thickness 0.15)) (justify left bottom) hide)
    )
    (property "Voltage" "50V" (at 13.335 86.36 0)
      (effects (font (size 1.27 1.27)) (justify left bottom) hide)
    )
    (property "Dielectric" "X5R" (at 10.795 86.36 0)
      (effects (font (size 1.27 1.27)) (justify left bottom) hide)
    )
    (pin "1")
    (pin "2")
    (instances
      (project "data-center-rdimm-ddr4-tester"
        (path ""
          (reference "C184") (unit 1)
        )
      )
    )
  )

  (symbol (lib_id "antmicroCapacitors0402:C_4u7_0402") (at 55.245 66.04 270) (unit 1)
    (in_bom yes) (on_board yes) (dnp no)
    (property "Reference" "C187" (at 55.88 66.675 90)
      (effects (font (size 1.524 1.524)) (justify left))
    )
    (property "Value" "C_4u7_0402" (at 45.085 86.36 0)
      (effects (font (size 1.27 1.27) (thickness 0.15)) (justify left bottom) hide)
    )
    (property "Footprint" "antmicro-footprints:C_0402_1005Metric" (at 42.545 86.36 0)
      (effects (font (size 1.27 1.27) (thickness 0.15)) (justify left bottom) hide)
    )
    (property "Datasheet" " " (at 40.005 86.36 0)
      (effects (font (size 1.27 1.27) (thickness 0.15)) (justify left bottom) hide)
    )
    (property "Manufacturer" "Murata" (at 34.925 86.36 0)
      (effects (font (size 1.27 1.27) (thickness 0.15)) (justify left bottom) hide)
    )
    (property "MPN" "GRM155R61A475MEAAD" (at 37.465 86.36 0)
      (effects (font (size 1.27 1.27) (thickness 0.15)) (justify left bottom) hide)
    )
    (property "Val" "4u7" (at 55.88 70.485 90)
      (effects (font (size 1.27 1.27) (thickness 0.15)) (justify left))
    )
    (property "License" "Apache-2.0" (at 32.385 86.36 0)
      (effects (font (size 1.27 1.27) (thickness 0.15)) (justify left bottom) hide)
    )
    (property "Author" "Antmicro" (at 29.845 86.36 0)
      (effects (font (size 1.27 1.27) (thickness 0.15)) (justify left bottom) hide)
    )
    (property "Voltage" "" (at 27.305 86.36 0)
      (effects (font (size 1.27 1.27)) (justify left bottom) hide)
    )
    (property "Dielectric" "" (at 24.765 86.36 0)
      (effects (font (size 1.27 1.27)) (justify left bottom) hide)
    )
    (pin "1")
    (pin "2")
    (instances
      (project "data-center-rdimm-ddr4-tester"
        (path ""
          (reference "C187") (unit 1)
        )
      )
    )
  )

  (symbol (lib_id "antmicropower:GND") (at 41.275 78.105 0) (unit 1)
    (in_bom yes) (on_board yes) (dnp no) (fields_autoplaced)
    (property "Reference" "#PWR0211" (at 41.275 84.455 0)
      (effects (font (size 1.27 1.27)) hide)
    )
    (property "Value" "GND" (at 41.275 83.185 0)
      (effects (font (size 1.27 1.27)))
    )
    (property "Footprint" "" (at 41.275 78.105 0)
      (effects (font (size 1.27 1.27)) hide)
    )
    (property "Datasheet" "" (at 41.275 78.105 0)
      (effects (font (size 1.27 1.27)) hide)
    )
    (property "Author" "Antmicro" (at 50.165 85.725 0)
      (effects (font (size 1.27 1.27) (thickness 0.15)) (justify left bottom) hide)
    )
    (property "License" "Apache-2.0" (at 50.165 88.265 0)
      (effects (font (size 1.27 1.27) (thickness 0.15)) (justify left bottom) hide)
    )
    (pin "1")
    (instances
      (project "data-center-rdimm-ddr4-tester"
        (path ""
          (reference "#PWR0211") (unit 1)
        )
      )
    )
  )

  (symbol (lib_id "antmicroResistors0402:R_12k_0402") (at 78.105 136.525 90) (unit 1)
    (in_bom yes) (on_board yes) (dnp no) (fields_autoplaced)
    (property "Reference" "R129" (at 76.2 132.715 90)
      (effects (font (size 1.524 1.524)) (justify left))
    )
    (property "Value" "R_12k_0402" (at 90.805 116.205 0)
      (effects (font (size 1.27 1.27) (thickness 0.15)) (justify left bottom) hide)
    )
    (property "Footprint" "antmicro-footprints:R_0402_1005Metric" (at 93.345 116.205 0)
      (effects (font (size 1.27 1.27) (thickness 0.15)) (justify left bottom) hide)
    )
    (property "Datasheet" "https://www.bourns.com/docs/product-datasheets/cr.pdf" (at 95.885 116.205 0)
      (effects (font (size 1.27 1.27) (thickness 0.15)) (justify left bottom) hide)
    )
    (property "Manufacturer" "Bourns" (at 100.965 116.205 0)
      (effects (font (size 1.27 1.27) (thickness 0.15)) (justify left bottom) hide)
    )
    (property "MPN" "CR0402-FX-1202GLF" (at 98.425 116.205 0)
      (effects (font (size 1.27 1.27) (thickness 0.15)) (justify left bottom) hide)
    )
    (property "Val" "12k" (at 76.2 135.8899 90)
      (effects (font (size 1.27 1.27) (thickness 0.15)) (justify left))
    )
    (property "License" "Apache-2.0" (at 103.505 116.205 0)
      (effects (font (size 1.27 1.27) (thickness 0.15)) (justify left bottom) hide)
    )
    (property "Author" "Antmicro" (at 106.045 116.205 0)
      (effects (font (size 1.27 1.27) (thickness 0.15)) (justify left bottom) hide)
    )
    (property "Tolerance" "1%" (at 88.265 116.205 0)
      (effects (font (size 1.27 1.27)) (justify left bottom) hide)
    )
    (pin "1")
    (pin "2")
    (instances
      (project "data-center-rdimm-ddr4-tester"
        (path ""
          (reference "R129") (unit 1)
        )
      )
    )
  )

  (symbol (lib_id "antmicroResistors0402:R_10k_0402") (at 72.39 87.63 0) (unit 1)
    (in_bom yes) (on_board yes) (dnp no)
    (property "Reference" "R130" (at 74.93 82.55 0)
      (effects (font (size 1.524 1.524)))
    )
    (property "Value" "R_10k_0402" (at 92.71 100.33 0)
      (effects (font (size 1.27 1.27) (thickness 0.15)) (justify left bottom) hide)
    )
    (property "Footprint" "antmicro-footprints:R_0402_1005Metric" (at 92.71 102.87 0)
      (effects (font (size 1.27 1.27) (thickness 0.15)) (justify left bottom) hide)
    )
    (property "Datasheet" "https://www.bourns.com/docs/product-datasheets/cr.pdf" (at 92.71 105.41 0)
      (effects (font (size 1.27 1.27) (thickness 0.15)) (justify left bottom) hide)
    )
    (property "Manufacturer" "Bourns" (at 92.71 110.49 0)
      (effects (font (size 1.27 1.27) (thickness 0.15)) (justify left bottom) hide)
    )
    (property "MPN" "CR0402-FX-1002GLF" (at 92.71 107.95 0)
      (effects (font (size 1.27 1.27) (thickness 0.15)) (justify left bottom) hide)
    )
    (property "Val" "10k" (at 74.93 85.09 0)
      (effects (font (size 1.27 1.27) (thickness 0.15)))
    )
    (property "License" "Apache-2.0" (at 92.71 113.03 0)
      (effects (font (size 1.27 1.27) (thickness 0.15)) (justify left bottom) hide)
    )
    (property "Author" "Antmicro" (at 92.71 115.57 0)
      (effects (font (size 1.27 1.27) (thickness 0.15)) (justify left bottom) hide)
    )
    (property "Tolerance" "1%" (at 92.71 97.79 0)
      (effects (font (size 1.27 1.27)) (justify left bottom) hide)
    )
    (pin "1")
    (pin "2")
    (instances
      (project "data-center-rdimm-ddr4-tester"
        (path ""
          (reference "R130") (unit 1)
        )
      )
    )
  )

  (symbol (lib_id "antmicroCapacitors0402:C_18p_0402") (at 46.99 115.57 270) (unit 1)
    (in_bom yes) (on_board yes) (dnp no)
    (property "Reference" "C190" (at 47.625 116.205 90)
      (effects (font (size 1.524 1.524)) (justify left))
    )
    (property "Value" "C_18p_0402" (at 36.83 135.89 0)
      (effects (font (size 1.27 1.27) (thickness 0.15)) (justify left bottom) hide)
    )
    (property "Footprint" "antmicro-footprints:C_0402_1005Metric" (at 34.29 135.89 0)
      (effects (font (size 1.27 1.27) (thickness 0.15)) (justify left bottom) hide)
    )
    (property "Datasheet" " " (at 31.75 135.89 0)
      (effects (font (size 1.27 1.27) (thickness 0.15)) (justify left bottom) hide)
    )
    (property "Manufacturer" "Multicomp" (at 26.67 135.89 0)
      (effects (font (size 1.27 1.27) (thickness 0.15)) (justify left bottom) hide)
    )
    (property "MPN" "MC0402N180J500CT" (at 29.21 135.89 0)
      (effects (font (size 1.27 1.27) (thickness 0.15)) (justify left bottom) hide)
    )
    (property "Val" "18p" (at 47.625 120.015 90)
      (effects (font (size 1.27 1.27) (thickness 0.15)) (justify left))
    )
    (property "License" "Apache-2.0" (at 24.13 135.89 0)
      (effects (font (size 1.27 1.27) (thickness 0.15)) (justify left bottom) hide)
    )
    (property "Author" "Antmicro" (at 21.59 135.89 0)
      (effects (font (size 1.27 1.27) (thickness 0.15)) (justify left bottom) hide)
    )
    (property "Voltage" "" (at 19.05 135.89 0)
      (effects (font (size 1.27 1.27)) (justify left bottom) hide)
    )
    (property "Dielectric" "" (at 16.51 135.89 0)
      (effects (font (size 1.27 1.27)) (justify left bottom) hide)
    )
    (pin "1")
    (pin "2")
    (instances
      (project "data-center-rdimm-ddr4-tester"
        (path ""
          (reference "C190") (unit 1)
        )
      )
    )
  )

  (symbol (lib_id "antmicroCapacitors0402:C_18p_0402") (at 67.31 115.57 270) (unit 1)
    (in_bom yes) (on_board yes) (dnp no)
    (property "Reference" "C193" (at 67.945 116.205 90)
      (effects (font (size 1.524 1.524)) (justify left))
    )
    (property "Value" "C_18p_0402" (at 57.15 135.89 0)
      (effects (font (size 1.27 1.27) (thickness 0.15)) (justify left bottom) hide)
    )
    (property "Footprint" "antmicro-footprints:C_0402_1005Metric" (at 54.61 135.89 0)
      (effects (font (size 1.27 1.27) (thickness 0.15)) (justify left bottom) hide)
    )
    (property "Datasheet" " " (at 52.07 135.89 0)
      (effects (font (size 1.27 1.27) (thickness 0.15)) (justify left bottom) hide)
    )
    (property "Manufacturer" "Multicomp" (at 46.99 135.89 0)
      (effects (font (size 1.27 1.27) (thickness 0.15)) (justify left bottom) hide)
    )
    (property "MPN" "MC0402N180J500CT" (at 49.53 135.89 0)
      (effects (font (size 1.27 1.27) (thickness 0.15)) (justify left bottom) hide)
    )
    (property "Val" "18p" (at 67.945 120.015 90)
      (effects (font (size 1.27 1.27) (thickness 0.15)) (justify left))
    )
    (property "License" "Apache-2.0" (at 44.45 135.89 0)
      (effects (font (size 1.27 1.27) (thickness 0.15)) (justify left bottom) hide)
    )
    (property "Author" "Antmicro" (at 41.91 135.89 0)
      (effects (font (size 1.27 1.27) (thickness 0.15)) (justify left bottom) hide)
    )
    (property "Voltage" "" (at 39.37 135.89 0)
      (effects (font (size 1.27 1.27)) (justify left bottom) hide)
    )
    (property "Dielectric" "" (at 36.83 135.89 0)
      (effects (font (size 1.27 1.27)) (justify left bottom) hide)
    )
    (pin "1")
    (pin "2")
    (instances
      (project "data-center-rdimm-ddr4-tester"
        (path ""
          (reference "C193") (unit 1)
        )
      )
    )
  )

  (symbol (lib_id "antmicropower:GND") (at 78.105 144.145 0) (unit 1)
    (in_bom yes) (on_board yes) (dnp no) (fields_autoplaced)
    (property "Reference" "#PWR0213" (at 78.105 150.495 0)
      (effects (font (size 1.27 1.27)) hide)
    )
    (property "Value" "GND" (at 78.105 149.225 0)
      (effects (font (size 1.27 1.27)))
    )
    (property "Footprint" "" (at 78.105 144.145 0)
      (effects (font (size 1.27 1.27)) hide)
    )
    (property "Datasheet" "" (at 78.105 144.145 0)
      (effects (font (size 1.27 1.27)) hide)
    )
    (property "Author" "Antmicro" (at 86.995 151.765 0)
      (effects (font (size 1.27 1.27) (thickness 0.15)) (justify left bottom) hide)
    )
    (property "License" "Apache-2.0" (at 86.995 154.305 0)
      (effects (font (size 1.27 1.27) (thickness 0.15)) (justify left bottom) hide)
    )
    (pin "1")
    (instances
      (project "data-center-rdimm-ddr4-tester"
        (path ""
          (reference "#PWR0213") (unit 1)
        )
      )
    )
  )

  (symbol (lib_id "antmicropower:GND") (at 67.31 120.65 0) (unit 1)
    (in_bom yes) (on_board yes) (dnp no) (fields_autoplaced)
    (property "Reference" "#PWR0215" (at 67.31 127 0)
      (effects (font (size 1.27 1.27)) hide)
    )
    (property "Value" "GND" (at 67.31 125.73 0)
      (effects (font (size 1.27 1.27)))
    )
    (property "Footprint" "" (at 67.31 120.65 0)
      (effects (font (size 1.27 1.27)) hide)
    )
    (property "Datasheet" "" (at 67.31 120.65 0)
      (effects (font (size 1.27 1.27)) hide)
    )
    (property "Author" "Antmicro" (at 76.2 128.27 0)
      (effects (font (size 1.27 1.27) (thickness 0.15)) (justify left bottom) hide)
    )
    (property "License" "Apache-2.0" (at 76.2 130.81 0)
      (effects (font (size 1.27 1.27) (thickness 0.15)) (justify left bottom) hide)
    )
    (pin "1")
    (instances
      (project "data-center-rdimm-ddr4-tester"
        (path ""
          (reference "#PWR0215") (unit 1)
        )
      )
    )
  )

  (symbol (lib_id "antmicropower:GND") (at 46.99 120.65 0) (unit 1)
    (in_bom yes) (on_board yes) (dnp no) (fields_autoplaced)
    (property "Reference" "#PWR0216" (at 46.99 127 0)
      (effects (font (size 1.27 1.27)) hide)
    )
    (property "Value" "GND" (at 46.99 125.73 0)
      (effects (font (size 1.27 1.27)))
    )
    (property "Footprint" "" (at 46.99 120.65 0)
      (effects (font (size 1.27 1.27)) hide)
    )
    (property "Datasheet" "" (at 46.99 120.65 0)
      (effects (font (size 1.27 1.27)) hide)
    )
    (property "Author" "Antmicro" (at 55.88 128.27 0)
      (effects (font (size 1.27 1.27) (thickness 0.15)) (justify left bottom) hide)
    )
    (property "License" "Apache-2.0" (at 55.88 130.81 0)
      (effects (font (size 1.27 1.27) (thickness 0.15)) (justify left bottom) hide)
    )
    (pin "1")
    (instances
      (project "data-center-rdimm-ddr4-tester"
        (path ""
          (reference "#PWR0216") (unit 1)
        )
      )
    )
  )

  (symbol (lib_id "antmicroCapacitors0402:C_100n_0402") (at 60.96 161.29 270) (unit 1)
    (in_bom yes) (on_board yes) (dnp no)
    (property "Reference" "C186" (at 61.595 161.925 90)
      (effects (font (size 1.524 1.524)) (justify left))
    )
    (property "Value" "C_100n_0402" (at 50.8 181.61 0)
      (effects (font (size 1.27 1.27) (thickness 0.15)) (justify left bottom) hide)
    )
    (property "Footprint" "antmicro-footprints:C_0402_1005Metric" (at 48.26 181.61 0)
      (effects (font (size 1.27 1.27) (thickness 0.15)) (justify left bottom) hide)
    )
    (property "Datasheet" "https://search.murata.co.jp/Ceramy/image/img/A01X/G101/ENG/GRM155R61H104KE14-01.pdf" (at 45.72 181.61 0)
      (effects (font (size 1.27 1.27) (thickness 0.15)) (justify left bottom) hide)
    )
    (property "Manufacturer" "Murata" (at 40.64 181.61 0)
      (effects (font (size 1.27 1.27) (thickness 0.15)) (justify left bottom) hide)
    )
    (property "MPN" "GRM155R61H104KE14D" (at 43.18 181.61 0)
      (effects (font (size 1.27 1.27) (thickness 0.15)) (justify left bottom) hide)
    )
    (property "Val" "100n" (at 61.595 165.735 90)
      (effects (font (size 1.27 1.27) (thickness 0.15)) (justify left))
    )
    (property "License" "Apache-2.0" (at 38.1 181.61 0)
      (effects (font (size 1.27 1.27) (thickness 0.15)) (justify left bottom) hide)
    )
    (property "Author" "Antmicro" (at 35.56 181.61 0)
      (effects (font (size 1.27 1.27) (thickness 0.15)) (justify left bottom) hide)
    )
    (property "Voltage" "50V" (at 33.02 181.61 0)
      (effects (font (size 1.27 1.27)) (justify left bottom) hide)
    )
    (property "Dielectric" "X5R" (at 30.48 181.61 0)
      (effects (font (size 1.27 1.27)) (justify left bottom) hide)
    )
    (pin "1")
    (pin "2")
    (instances
      (project "data-center-rdimm-ddr4-tester"
        (path ""
          (reference "C186") (unit 1)
        )
      )
    )
  )

  (symbol (lib_id "antmicroCapacitors0402:C_100n_0402") (at 68.58 161.29 270) (unit 1)
    (in_bom yes) (on_board yes) (dnp no)
    (property "Reference" "C188" (at 69.215 161.9251 90)
      (effects (font (size 1.524 1.524)) (justify left))
    )
    (property "Value" "C_100n_0402" (at 58.42 181.61 0)
      (effects (font (size 1.27 1.27) (thickness 0.15)) (justify left bottom) hide)
    )
    (property "Footprint" "antmicro-footprints:C_0402_1005Metric" (at 55.88 181.61 0)
      (effects (font (size 1.27 1.27) (thickness 0.15)) (justify left bottom) hide)
    )
    (property "Datasheet" "https://search.murata.co.jp/Ceramy/image/img/A01X/G101/ENG/GRM155R61H104KE14-01.pdf" (at 53.34 181.61 0)
      (effects (font (size 1.27 1.27) (thickness 0.15)) (justify left bottom) hide)
    )
    (property "Manufacturer" "Murata" (at 48.26 181.61 0)
      (effects (font (size 1.27 1.27) (thickness 0.15)) (justify left bottom) hide)
    )
    (property "MPN" "GRM155R61H104KE14D" (at 50.8 181.61 0)
      (effects (font (size 1.27 1.27) (thickness 0.15)) (justify left bottom) hide)
    )
    (property "Val" "100n" (at 69.215 165.735 90)
      (effects (font (size 1.27 1.27) (thickness 0.15)) (justify left))
    )
    (property "License" "Apache-2.0" (at 45.72 181.61 0)
      (effects (font (size 1.27 1.27) (thickness 0.15)) (justify left bottom) hide)
    )
    (property "Author" "Antmicro" (at 43.18 181.61 0)
      (effects (font (size 1.27 1.27) (thickness 0.15)) (justify left bottom) hide)
    )
    (property "Voltage" "50V" (at 40.64 181.61 0)
      (effects (font (size 1.27 1.27)) (justify left bottom) hide)
    )
    (property "Dielectric" "X5R" (at 38.1 181.61 0)
      (effects (font (size 1.27 1.27)) (justify left bottom) hide)
    )
    (pin "1")
    (pin "2")
    (instances
      (project "data-center-rdimm-ddr4-tester"
        (path ""
          (reference "C188") (unit 1)
        )
      )
    )
  )

  (symbol (lib_id "antmicroCapacitors0402:C_100n_0402") (at 76.2 161.29 270) (unit 1)
    (in_bom yes) (on_board yes) (dnp no)
    (property "Reference" "C191" (at 76.835 161.9251 90)
      (effects (font (size 1.524 1.524)) (justify left))
    )
    (property "Value" "C_100n_0402" (at 66.04 181.61 0)
      (effects (font (size 1.27 1.27) (thickness 0.15)) (justify left bottom) hide)
    )
    (property "Footprint" "antmicro-footprints:C_0402_1005Metric" (at 63.5 181.61 0)
      (effects (font (size 1.27 1.27) (thickness 0.15)) (justify left bottom) hide)
    )
    (property "Datasheet" "https://search.murata.co.jp/Ceramy/image/img/A01X/G101/ENG/GRM155R61H104KE14-01.pdf" (at 60.96 181.61 0)
      (effects (font (size 1.27 1.27) (thickness 0.15)) (justify left bottom) hide)
    )
    (property "Manufacturer" "Murata" (at 55.88 181.61 0)
      (effects (font (size 1.27 1.27) (thickness 0.15)) (justify left bottom) hide)
    )
    (property "MPN" "GRM155R61H104KE14D" (at 58.42 181.61 0)
      (effects (font (size 1.27 1.27) (thickness 0.15)) (justify left bottom) hide)
    )
    (property "Val" "100n" (at 76.835 165.735 90)
      (effects (font (size 1.27 1.27) (thickness 0.15)) (justify left))
    )
    (property "License" "Apache-2.0" (at 53.34 181.61 0)
      (effects (font (size 1.27 1.27) (thickness 0.15)) (justify left bottom) hide)
    )
    (property "Author" "Antmicro" (at 50.8 181.61 0)
      (effects (font (size 1.27 1.27) (thickness 0.15)) (justify left bottom) hide)
    )
    (property "Voltage" "50V" (at 48.26 181.61 0)
      (effects (font (size 1.27 1.27)) (justify left bottom) hide)
    )
    (property "Dielectric" "X5R" (at 45.72 181.61 0)
      (effects (font (size 1.27 1.27)) (justify left bottom) hide)
    )
    (pin "1")
    (pin "2")
    (instances
      (project "data-center-rdimm-ddr4-tester"
        (path ""
          (reference "C191") (unit 1)
        )
      )
    )
  )

  (symbol (lib_id "antmicroCapacitors0402:C_100n_0402") (at 83.82 161.29 270) (unit 1)
    (in_bom yes) (on_board yes) (dnp no)
    (property "Reference" "C192" (at 84.455 161.9251 90)
      (effects (font (size 1.524 1.524)) (justify left))
    )
    (property "Value" "C_100n_0402" (at 73.66 181.61 0)
      (effects (font (size 1.27 1.27) (thickness 0.15)) (justify left bottom) hide)
    )
    (property "Footprint" "antmicro-footprints:C_0402_1005Metric" (at 71.12 181.61 0)
      (effects (font (size 1.27 1.27) (thickness 0.15)) (justify left bottom) hide)
    )
    (property "Datasheet" "https://search.murata.co.jp/Ceramy/image/img/A01X/G101/ENG/GRM155R61H104KE14-01.pdf" (at 68.58 181.61 0)
      (effects (font (size 1.27 1.27) (thickness 0.15)) (justify left bottom) hide)
    )
    (property "Manufacturer" "Murata" (at 63.5 181.61 0)
      (effects (font (size 1.27 1.27) (thickness 0.15)) (justify left bottom) hide)
    )
    (property "MPN" "GRM155R61H104KE14D" (at 66.04 181.61 0)
      (effects (font (size 1.27 1.27) (thickness 0.15)) (justify left bottom) hide)
    )
    (property "Val" "100n" (at 84.455 165.735 90)
      (effects (font (size 1.27 1.27) (thickness 0.15)) (justify left))
    )
    (property "License" "Apache-2.0" (at 60.96 181.61 0)
      (effects (font (size 1.27 1.27) (thickness 0.15)) (justify left bottom) hide)
    )
    (property "Author" "Antmicro" (at 58.42 181.61 0)
      (effects (font (size 1.27 1.27) (thickness 0.15)) (justify left bottom) hide)
    )
    (property "Voltage" "50V" (at 55.88 181.61 0)
      (effects (font (size 1.27 1.27)) (justify left bottom) hide)
    )
    (property "Dielectric" "X5R" (at 53.34 181.61 0)
      (effects (font (size 1.27 1.27)) (justify left bottom) hide)
    )
    (pin "1")
    (pin "2")
    (instances
      (project "data-center-rdimm-ddr4-tester"
        (path ""
          (reference "C192") (unit 1)
        )
      )
    )
  )

  (symbol (lib_id "antmicropower:GND") (at 60.96 166.37 0) (unit 1)
    (in_bom yes) (on_board yes) (dnp no) (fields_autoplaced)
    (property "Reference" "#PWR0217" (at 60.96 172.72 0)
      (effects (font (size 1.27 1.27)) hide)
    )
    (property "Value" "GND" (at 60.96 171.45 0)
      (effects (font (size 1.27 1.27)))
    )
    (property "Footprint" "" (at 60.96 166.37 0)
      (effects (font (size 1.27 1.27)) hide)
    )
    (property "Datasheet" "" (at 60.96 166.37 0)
      (effects (font (size 1.27 1.27)) hide)
    )
    (property "Author" "Antmicro" (at 69.85 173.99 0)
      (effects (font (size 1.27 1.27) (thickness 0.15)) (justify left bottom) hide)
    )
    (property "License" "Apache-2.0" (at 69.85 176.53 0)
      (effects (font (size 1.27 1.27) (thickness 0.15)) (justify left bottom) hide)
    )
    (pin "1")
    (instances
      (project "data-center-rdimm-ddr4-tester"
        (path ""
          (reference "#PWR0217") (unit 1)
        )
      )
    )
  )

  (symbol (lib_id "antmicropower:GND") (at 68.58 166.37 0) (unit 1)
    (in_bom yes) (on_board yes) (dnp no) (fields_autoplaced)
    (property "Reference" "#PWR0218" (at 68.58 172.72 0)
      (effects (font (size 1.27 1.27)) hide)
    )
    (property "Value" "GND" (at 68.58 171.45 0)
      (effects (font (size 1.27 1.27)))
    )
    (property "Footprint" "" (at 68.58 166.37 0)
      (effects (font (size 1.27 1.27)) hide)
    )
    (property "Datasheet" "" (at 68.58 166.37 0)
      (effects (font (size 1.27 1.27)) hide)
    )
    (property "Author" "Antmicro" (at 77.47 173.99 0)
      (effects (font (size 1.27 1.27) (thickness 0.15)) (justify left bottom) hide)
    )
    (property "License" "Apache-2.0" (at 77.47 176.53 0)
      (effects (font (size 1.27 1.27) (thickness 0.15)) (justify left bottom) hide)
    )
    (pin "1")
    (instances
      (project "data-center-rdimm-ddr4-tester"
        (path ""
          (reference "#PWR0218") (unit 1)
        )
      )
    )
  )

  (symbol (lib_id "antmicropower:GND") (at 76.2 166.37 0) (unit 1)
    (in_bom yes) (on_board yes) (dnp no) (fields_autoplaced)
    (property "Reference" "#PWR0219" (at 76.2 172.72 0)
      (effects (font (size 1.27 1.27)) hide)
    )
    (property "Value" "GND" (at 76.2 171.45 0)
      (effects (font (size 1.27 1.27)))
    )
    (property "Footprint" "" (at 76.2 166.37 0)
      (effects (font (size 1.27 1.27)) hide)
    )
    (property "Datasheet" "" (at 76.2 166.37 0)
      (effects (font (size 1.27 1.27)) hide)
    )
    (property "Author" "Antmicro" (at 85.09 173.99 0)
      (effects (font (size 1.27 1.27) (thickness 0.15)) (justify left bottom) hide)
    )
    (property "License" "Apache-2.0" (at 85.09 176.53 0)
      (effects (font (size 1.27 1.27) (thickness 0.15)) (justify left bottom) hide)
    )
    (pin "1")
    (instances
      (project "data-center-rdimm-ddr4-tester"
        (path ""
          (reference "#PWR0219") (unit 1)
        )
      )
    )
  )

  (symbol (lib_id "antmicropower:GND") (at 83.82 166.37 0) (unit 1)
    (in_bom yes) (on_board yes) (dnp no) (fields_autoplaced)
    (property "Reference" "#PWR0220" (at 83.82 172.72 0)
      (effects (font (size 1.27 1.27)) hide)
    )
    (property "Value" "GND" (at 83.82 171.45 0)
      (effects (font (size 1.27 1.27)))
    )
    (property "Footprint" "" (at 83.82 166.37 0)
      (effects (font (size 1.27 1.27)) hide)
    )
    (property "Datasheet" "" (at 83.82 166.37 0)
      (effects (font (size 1.27 1.27)) hide)
    )
    (property "Author" "Antmicro" (at 92.71 173.99 0)
      (effects (font (size 1.27 1.27) (thickness 0.15)) (justify left bottom) hide)
    )
    (property "License" "Apache-2.0" (at 92.71 176.53 0)
      (effects (font (size 1.27 1.27) (thickness 0.15)) (justify left bottom) hide)
    )
    (pin "1")
    (instances
      (project "data-center-rdimm-ddr4-tester"
        (path ""
          (reference "#PWR0220") (unit 1)
        )
      )
    )
  )

  (symbol (lib_id "antmicroCapacitors0402:C_100n_0402") (at 119.38 161.29 270) (unit 1)
    (in_bom yes) (on_board yes) (dnp no)
    (property "Reference" "C196" (at 120.015 161.925 90)
      (effects (font (size 1.524 1.524)) (justify left))
    )
    (property "Value" "C_100n_0402" (at 109.22 181.61 0)
      (effects (font (size 1.27 1.27) (thickness 0.15)) (justify left bottom) hide)
    )
    (property "Footprint" "antmicro-footprints:C_0402_1005Metric" (at 106.68 181.61 0)
      (effects (font (size 1.27 1.27) (thickness 0.15)) (justify left bottom) hide)
    )
    (property "Datasheet" "https://search.murata.co.jp/Ceramy/image/img/A01X/G101/ENG/GRM155R61H104KE14-01.pdf" (at 104.14 181.61 0)
      (effects (font (size 1.27 1.27) (thickness 0.15)) (justify left bottom) hide)
    )
    (property "Manufacturer" "Murata" (at 99.06 181.61 0)
      (effects (font (size 1.27 1.27) (thickness 0.15)) (justify left bottom) hide)
    )
    (property "MPN" "GRM155R61H104KE14D" (at 101.6 181.61 0)
      (effects (font (size 1.27 1.27) (thickness 0.15)) (justify left bottom) hide)
    )
    (property "Val" "100n" (at 120.015 165.735 90)
      (effects (font (size 1.27 1.27) (thickness 0.15)) (justify left))
    )
    (property "License" "Apache-2.0" (at 96.52 181.61 0)
      (effects (font (size 1.27 1.27) (thickness 0.15)) (justify left bottom) hide)
    )
    (property "Author" "Antmicro" (at 93.98 181.61 0)
      (effects (font (size 1.27 1.27) (thickness 0.15)) (justify left bottom) hide)
    )
    (property "Voltage" "50V" (at 91.44 181.61 0)
      (effects (font (size 1.27 1.27)) (justify left bottom) hide)
    )
    (property "Dielectric" "X5R" (at 88.9 181.61 0)
      (effects (font (size 1.27 1.27)) (justify left bottom) hide)
    )
    (pin "1")
    (pin "2")
    (instances
      (project "data-center-rdimm-ddr4-tester"
        (path ""
          (reference "C196") (unit 1)
        )
      )
    )
  )

  (symbol (lib_id "antmicroCapacitors0402:C_100n_0402") (at 127 161.29 270) (unit 1)
    (in_bom yes) (on_board yes) (dnp no)
    (property "Reference" "C197" (at 127.635 161.925 90)
      (effects (font (size 1.524 1.524)) (justify left))
    )
    (property "Value" "C_100n_0402" (at 116.84 181.61 0)
      (effects (font (size 1.27 1.27) (thickness 0.15)) (justify left bottom) hide)
    )
    (property "Footprint" "antmicro-footprints:C_0402_1005Metric" (at 114.3 181.61 0)
      (effects (font (size 1.27 1.27) (thickness 0.15)) (justify left bottom) hide)
    )
    (property "Datasheet" "https://search.murata.co.jp/Ceramy/image/img/A01X/G101/ENG/GRM155R61H104KE14-01.pdf" (at 111.76 181.61 0)
      (effects (font (size 1.27 1.27) (thickness 0.15)) (justify left bottom) hide)
    )
    (property "Manufacturer" "Murata" (at 106.68 181.61 0)
      (effects (font (size 1.27 1.27) (thickness 0.15)) (justify left bottom) hide)
    )
    (property "MPN" "GRM155R61H104KE14D" (at 109.22 181.61 0)
      (effects (font (size 1.27 1.27) (thickness 0.15)) (justify left bottom) hide)
    )
    (property "Val" "100n" (at 127.635 165.735 90)
      (effects (font (size 1.27 1.27) (thickness 0.15)) (justify left))
    )
    (property "License" "Apache-2.0" (at 104.14 181.61 0)
      (effects (font (size 1.27 1.27) (thickness 0.15)) (justify left bottom) hide)
    )
    (property "Author" "Antmicro" (at 101.6 181.61 0)
      (effects (font (size 1.27 1.27) (thickness 0.15)) (justify left bottom) hide)
    )
    (property "Voltage" "50V" (at 99.06 181.61 0)
      (effects (font (size 1.27 1.27)) (justify left bottom) hide)
    )
    (property "Dielectric" "X5R" (at 96.52 181.61 0)
      (effects (font (size 1.27 1.27)) (justify left bottom) hide)
    )
    (pin "1")
    (pin "2")
    (instances
      (project "data-center-rdimm-ddr4-tester"
        (path ""
          (reference "C197") (unit 1)
        )
      )
    )
  )

  (symbol (lib_id "antmicropower:GND") (at 119.38 166.37 0) (unit 1)
    (in_bom yes) (on_board yes) (dnp no) (fields_autoplaced)
    (property "Reference" "#PWR0222" (at 119.38 172.72 0)
      (effects (font (size 1.27 1.27)) hide)
    )
    (property "Value" "GND" (at 119.38 171.45 0)
      (effects (font (size 1.27 1.27)))
    )
    (property "Footprint" "" (at 119.38 166.37 0)
      (effects (font (size 1.27 1.27)) hide)
    )
    (property "Datasheet" "" (at 119.38 166.37 0)
      (effects (font (size 1.27 1.27)) hide)
    )
    (property "Author" "Antmicro" (at 128.27 173.99 0)
      (effects (font (size 1.27 1.27) (thickness 0.15)) (justify left bottom) hide)
    )
    (property "License" "Apache-2.0" (at 128.27 176.53 0)
      (effects (font (size 1.27 1.27) (thickness 0.15)) (justify left bottom) hide)
    )
    (pin "1")
    (instances
      (project "data-center-rdimm-ddr4-tester"
        (path ""
          (reference "#PWR0222") (unit 1)
        )
      )
    )
  )

  (symbol (lib_id "antmicropower:GND") (at 127 166.37 0) (unit 1)
    (in_bom yes) (on_board yes) (dnp no) (fields_autoplaced)
    (property "Reference" "#PWR0223" (at 127 172.72 0)
      (effects (font (size 1.27 1.27)) hide)
    )
    (property "Value" "GND" (at 127 171.45 0)
      (effects (font (size 1.27 1.27)))
    )
    (property "Footprint" "" (at 127 166.37 0)
      (effects (font (size 1.27 1.27)) hide)
    )
    (property "Datasheet" "" (at 127 166.37 0)
      (effects (font (size 1.27 1.27)) hide)
    )
    (property "Author" "Antmicro" (at 135.89 173.99 0)
      (effects (font (size 1.27 1.27) (thickness 0.15)) (justify left bottom) hide)
    )
    (property "License" "Apache-2.0" (at 135.89 176.53 0)
      (effects (font (size 1.27 1.27) (thickness 0.15)) (justify left bottom) hide)
    )
    (pin "1")
    (instances
      (project "data-center-rdimm-ddr4-tester"
        (path ""
          (reference "#PWR0223") (unit 1)
        )
      )
    )
  )

  (symbol (lib_id "antmicroCapacitors0402:C_4u7_0402") (at 111.76 161.29 270) (unit 1)
    (in_bom yes) (on_board yes) (dnp no)
    (property "Reference" "C195" (at 112.395 161.925 90)
      (effects (font (size 1.524 1.524)) (justify left))
    )
    (property "Value" "C_4u7_0402" (at 101.6 181.61 0)
      (effects (font (size 1.27 1.27) (thickness 0.15)) (justify left bottom) hide)
    )
    (property "Footprint" "antmicro-footprints:C_0402_1005Metric" (at 99.06 181.61 0)
      (effects (font (size 1.27 1.27) (thickness 0.15)) (justify left bottom) hide)
    )
    (property "Datasheet" " " (at 96.52 181.61 0)
      (effects (font (size 1.27 1.27) (thickness 0.15)) (justify left bottom) hide)
    )
    (property "Manufacturer" "Murata" (at 91.44 181.61 0)
      (effects (font (size 1.27 1.27) (thickness 0.15)) (justify left bottom) hide)
    )
    (property "MPN" "GRM155R61A475MEAAD" (at 93.98 181.61 0)
      (effects (font (size 1.27 1.27) (thickness 0.15)) (justify left bottom) hide)
    )
    (property "Val" "4u7" (at 112.395 165.735 90)
      (effects (font (size 1.27 1.27) (thickness 0.15)) (justify left))
    )
    (property "License" "Apache-2.0" (at 88.9 181.61 0)
      (effects (font (size 1.27 1.27) (thickness 0.15)) (justify left bottom) hide)
    )
    (property "Author" "Antmicro" (at 86.36 181.61 0)
      (effects (font (size 1.27 1.27) (thickness 0.15)) (justify left bottom) hide)
    )
    (property "Voltage" "" (at 83.82 181.61 0)
      (effects (font (size 1.27 1.27)) (justify left bottom) hide)
    )
    (property "Dielectric" "" (at 81.28 181.61 0)
      (effects (font (size 1.27 1.27)) (justify left bottom) hide)
    )
    (pin "1")
    (pin "2")
    (instances
      (project "data-center-rdimm-ddr4-tester"
        (path ""
          (reference "C195") (unit 1)
        )
      )
    )
  )

  (symbol (lib_id "antmicropower:GND") (at 111.76 166.37 0) (unit 1)
    (in_bom yes) (on_board yes) (dnp no) (fields_autoplaced)
    (property "Reference" "#PWR0225" (at 111.76 172.72 0)
      (effects (font (size 1.27 1.27)) hide)
    )
    (property "Value" "GND" (at 111.76 171.45 0)
      (effects (font (size 1.27 1.27)))
    )
    (property "Footprint" "" (at 111.76 166.37 0)
      (effects (font (size 1.27 1.27)) hide)
    )
    (property "Datasheet" "" (at 111.76 166.37 0)
      (effects (font (size 1.27 1.27)) hide)
    )
    (property "Author" "Antmicro" (at 120.65 173.99 0)
      (effects (font (size 1.27 1.27) (thickness 0.15)) (justify left bottom) hide)
    )
    (property "License" "Apache-2.0" (at 120.65 176.53 0)
      (effects (font (size 1.27 1.27) (thickness 0.15)) (justify left bottom) hide)
    )
    (pin "1")
    (instances
      (project "data-center-rdimm-ddr4-tester"
        (path ""
          (reference "#PWR0225") (unit 1)
        )
      )
    )
  )

  (symbol (lib_id "antmicropower:GND") (at 62.865 235.585 90) (unit 1)
    (in_bom yes) (on_board yes) (dnp no) (fields_autoplaced)
    (property "Reference" "#PWR0168" (at 69.215 235.585 0)
      (effects (font (size 1.27 1.27)) hide)
    )
    (property "Value" "GND" (at 66.04 235.5849 90)
      (effects (font (size 1.27 1.27)) (justify right))
    )
    (property "Footprint" "" (at 62.865 235.585 0)
      (effects (font (size 1.27 1.27)) hide)
    )
    (property "Datasheet" "" (at 62.865 235.585 0)
      (effects (font (size 1.27 1.27)) hide)
    )
    (property "Author" "Antmicro" (at 70.485 226.695 0)
      (effects (font (size 1.27 1.27) (thickness 0.15)) (justify left bottom) hide)
    )
    (property "License" "Apache-2.0" (at 73.025 226.695 0)
      (effects (font (size 1.27 1.27) (thickness 0.15)) (justify left bottom) hide)
    )
    (pin "1")
    (instances
      (project "data-center-rdimm-ddr4-tester"
        (path ""
          (reference "#PWR0168") (unit 1)
        )
      )
    )
  )

  (symbol (lib_id "antmicroResistors0402:R_330R_0402") (at 38.735 235.585 0) (unit 1)
    (in_bom yes) (on_board yes) (dnp no)
    (property "Reference" "R52" (at 41.275 238.76 0)
      (effects (font (size 1.524 1.524)))
    )
    (property "Value" "R_330R_0402" (at 59.055 248.285 0)
      (effects (font (size 1.27 1.27) (thickness 0.15)) (justify left bottom) hide)
    )
    (property "Footprint" "antmicro-footprints:R_0402_1005Metric" (at 59.055 250.825 0)
      (effects (font (size 1.27 1.27) (thickness 0.15)) (justify left bottom) hide)
    )
    (property "Datasheet" "https://www.bourns.com/docs/product-datasheets/cr.pdf" (at 59.055 253.365 0)
      (effects (font (size 1.27 1.27) (thickness 0.15)) (justify left bottom) hide)
    )
    (property "Manufacturer" "Bourns" (at 59.055 258.445 0)
      (effects (font (size 1.27 1.27) (thickness 0.15)) (justify left bottom) hide)
    )
    (property "MPN" "CR0402-FX-3300GLF" (at 59.055 255.905 0)
      (effects (font (size 1.27 1.27) (thickness 0.15)) (justify left bottom) hide)
    )
    (property "Val" "330R" (at 41.275 241.3 0)
      (effects (font (size 1.27 1.27) (thickness 0.15)))
    )
    (property "License" "Apache-2.0" (at 59.055 260.985 0)
      (effects (font (size 1.27 1.27) (thickness 0.15)) (justify left bottom) hide)
    )
    (property "Author" "Antmicro" (at 59.055 263.525 0)
      (effects (font (size 1.27 1.27) (thickness 0.15)) (justify left bottom) hide)
    )
    (property "Tolerance" "1%" (at 59.055 245.745 0)
      (effects (font (size 1.27 1.27)) (justify left bottom) hide)
    )
    (pin "1")
    (pin "2")
    (instances
      (project "data-center-rdimm-ddr4-tester"
        (path ""
          (reference "R52") (unit 1)
        )
      )
    )
  )

  (symbol (lib_id "antmicroLEDIndicationDiscrete:LED_G_0603_KP-1608CGCK") (at 28.575 235.585 0) (unit 1)
    (in_bom yes) (on_board yes) (dnp no) (fields_autoplaced)
    (property "Reference" "D7" (at 32.385 227.33 0)
      (effects (font (size 1.524 1.524)))
    )
    (property "Value" "LED_G_0603_KP-1608CGCK" (at 32.385 231.14 0)
      (effects (font (size 1.27 1.27) (thickness 0.15)) hide)
    )
    (property "Footprint" "antmicro-footprints:LED_0603_1608Metric_G" (at 51.435 245.745 0)
      (effects (font (size 1.27 1.27) (thickness 0.15)) (justify left bottom) hide)
    )
    (property "Datasheet" "http://www.farnell.com/datasheets/2045956.pdf" (at 51.435 248.285 0)
      (effects (font (size 1.27 1.27) (thickness 0.15)) (justify left bottom) hide)
    )
    (property "MPN" "KP-1608CGCK" (at 32.385 231.14 0)
      (effects (font (size 1.27 1.27) (thickness 0.15)))
    )
    (property "Manufacturer" "Kingbright" (at 51.435 253.365 0)
      (effects (font (size 1.27 1.27) (thickness 0.15)) (justify left bottom) hide)
    )
    (property "Author" "Antmicro" (at 51.435 255.905 0)
      (effects (font (size 1.27 1.27) (thickness 0.15)) (justify left bottom) hide)
    )
    (property "License" "Apache-2.0" (at 51.435 258.445 0)
      (effects (font (size 1.27 1.27) (thickness 0.15)) (justify left bottom) hide)
    )
    (pin "1")
    (pin "2")
    (instances
      (project "data-center-rdimm-ddr4-tester"
        (path ""
          (reference "D7") (unit 1)
        )
      )
    )
  )

  (symbol (lib_id "antmicropower:GND") (at 230.505 184.785 0) (unit 1)
    (in_bom yes) (on_board yes) (dnp no)
    (property "Reference" "#PWR0227" (at 230.505 191.135 0)
      (effects (font (size 1.27 1.27)) hide)
    )
    (property "Value" "GND" (at 230.505 189.23 0)
      (effects (font (size 1.27 1.27)))
    )
    (property "Footprint" "" (at 230.505 184.785 0)
      (effects (font (size 1.27 1.27)) hide)
    )
    (property "Datasheet" "" (at 230.505 184.785 0)
      (effects (font (size 1.27 1.27)) hide)
    )
    (property "Author" "Antmicro" (at 239.395 192.405 0)
      (effects (font (size 1.27 1.27) (thickness 0.15)) (justify left bottom) hide)
    )
    (property "License" "Apache-2.0" (at 239.395 194.945 0)
      (effects (font (size 1.27 1.27) (thickness 0.15)) (justify left bottom) hide)
    )
    (pin "1")
    (instances
      (project "data-center-rdimm-ddr4-tester"
        (path ""
          (reference "#PWR0227") (unit 1)
        )
      )
    )
  )

  (symbol (lib_id "antmicropower:GND") (at 117.475 215.9 90) (unit 1)
    (in_bom yes) (on_board yes) (dnp no) (fields_autoplaced)
    (property "Reference" "#PWR0169" (at 123.825 215.9 0)
      (effects (font (size 1.27 1.27)) hide)
    )
    (property "Value" "GND" (at 120.65 215.8999 90)
      (effects (font (size 1.27 1.27)) (justify right))
    )
    (property "Footprint" "" (at 117.475 215.9 0)
      (effects (font (size 1.27 1.27)) hide)
    )
    (property "Datasheet" "" (at 117.475 215.9 0)
      (effects (font (size 1.27 1.27)) hide)
    )
    (property "Author" "Antmicro" (at 125.095 207.01 0)
      (effects (font (size 1.27 1.27) (thickness 0.15)) (justify left bottom) hide)
    )
    (property "License" "Apache-2.0" (at 127.635 207.01 0)
      (effects (font (size 1.27 1.27) (thickness 0.15)) (justify left bottom) hide)
    )
    (pin "1")
    (instances
      (project "data-center-rdimm-ddr4-tester"
        (path ""
          (reference "#PWR0169") (unit 1)
        )
      )
    )
  )

  (symbol (lib_id "antmicroResistors0402:R_330R_0402") (at 93.345 215.9 0) (unit 1)
    (in_bom yes) (on_board yes) (dnp no)
    (property "Reference" "R53" (at 95.885 219.075 0)
      (effects (font (size 1.524 1.524)))
    )
    (property "Value" "R_330R_0402" (at 113.665 228.6 0)
      (effects (font (size 1.27 1.27) (thickness 0.15)) (justify left bottom) hide)
    )
    (property "Footprint" "antmicro-footprints:R_0402_1005Metric" (at 113.665 231.14 0)
      (effects (font (size 1.27 1.27) (thickness 0.15)) (justify left bottom) hide)
    )
    (property "Datasheet" "https://www.bourns.com/docs/product-datasheets/cr.pdf" (at 113.665 233.68 0)
      (effects (font (size 1.27 1.27) (thickness 0.15)) (justify left bottom) hide)
    )
    (property "Manufacturer" "Bourns" (at 113.665 238.76 0)
      (effects (font (size 1.27 1.27) (thickness 0.15)) (justify left bottom) hide)
    )
    (property "MPN" "CR0402-FX-3300GLF" (at 113.665 236.22 0)
      (effects (font (size 1.27 1.27) (thickness 0.15)) (justify left bottom) hide)
    )
    (property "Val" "330R" (at 95.885 221.615 0)
      (effects (font (size 1.27 1.27) (thickness 0.15)))
    )
    (property "License" "Apache-2.0" (at 113.665 241.3 0)
      (effects (font (size 1.27 1.27) (thickness 0.15)) (justify left bottom) hide)
    )
    (property "Author" "Antmicro" (at 113.665 243.84 0)
      (effects (font (size 1.27 1.27) (thickness 0.15)) (justify left bottom) hide)
    )
    (property "Tolerance" "1%" (at 113.665 226.06 0)
      (effects (font (size 1.27 1.27)) (justify left bottom) hide)
    )
    (pin "1")
    (pin "2")
    (instances
      (project "data-center-rdimm-ddr4-tester"
        (path ""
          (reference "R53") (unit 1)
        )
      )
    )
  )

  (symbol (lib_id "antmicroLEDIndicationDiscrete:LED_G_0603_KP-1608CGCK") (at 83.185 215.9 0) (unit 1)
    (in_bom yes) (on_board yes) (dnp no) (fields_autoplaced)
    (property "Reference" "D8" (at 86.995 208.28 0)
      (effects (font (size 1.524 1.524)))
    )
    (property "Value" "LED_G_0603_KP-1608CGCK" (at 86.995 210.82 0)
      (effects (font (size 1.27 1.27) (thickness 0.15)) hide)
    )
    (property "Footprint" "antmicro-footprints:LED_0603_1608Metric_G" (at 106.045 226.06 0)
      (effects (font (size 1.27 1.27) (thickness 0.15)) (justify left bottom) hide)
    )
    (property "Datasheet" "http://www.farnell.com/datasheets/2045956.pdf" (at 106.045 228.6 0)
      (effects (font (size 1.27 1.27) (thickness 0.15)) (justify left bottom) hide)
    )
    (property "MPN" "KP-1608CGCK" (at 86.995 210.82 0)
      (effects (font (size 1.27 1.27) (thickness 0.15)))
    )
    (property "Manufacturer" "Kingbright" (at 106.045 233.68 0)
      (effects (font (size 1.27 1.27) (thickness 0.15)) (justify left bottom) hide)
    )
    (property "Author" "Antmicro" (at 106.045 236.22 0)
      (effects (font (size 1.27 1.27) (thickness 0.15)) (justify left bottom) hide)
    )
    (property "License" "Apache-2.0" (at 106.045 238.76 0)
      (effects (font (size 1.27 1.27) (thickness 0.15)) (justify left bottom) hide)
    )
    (pin "1")
    (pin "2")
    (instances
      (project "data-center-rdimm-ddr4-tester"
        (path ""
          (reference "D8") (unit 1)
        )
      )
    )
  )

  (symbol (lib_id "antmicroTVSDiodes:TPD2E009_SOT-9X3") (at 221.615 177.165 0) (mirror y) (unit 1)
    (in_bom yes) (on_board yes) (dnp no)
    (property "Reference" "D3" (at 215.9 170.18 0)
      (effects (font (size 1.524 1.524)))
    )
    (property "Value" "TPD2E009_SOT-9X3" (at 213.9951 172.72 90)
      (effects (font (size 1.27 1.27) (thickness 0.15)) (justify left) hide)
    )
    (property "Footprint" "antmicro-footprints:SOT-723" (at 206.375 182.245 0)
      (effects (font (size 1.27 1.27) (thickness 0.15)) (justify left bottom) hide)
    )
    (property "Datasheet" "https://www.ti.com/lit/ds/symlink/tpd2e009.pdf?ts=1597910439511&ref_url=https%253A%252F%252Fwww.google.com%252F" (at 206.375 184.785 0)
      (effects (font (size 1.27 1.27) (thickness 0.15)) (justify left bottom) hide)
    )
    (property "MPN" "TPD2E009DRTR" (at 215.9 172.72 0)
      (effects (font (size 1.27 1.27) (thickness 0.15)))
    )
    (property "Manufacturer" "Texas Instruments" (at 206.375 189.865 0)
      (effects (font (size 1.27 1.27) (thickness 0.15)) (justify left bottom) hide)
    )
    (property "Author" "Antmicro" (at 206.375 192.405 0)
      (effects (font (size 1.27 1.27) (thickness 0.15)) (justify left bottom) hide)
    )
    (property "License" "Apache-2.0" (at 206.375 194.945 0)
      (effects (font (size 1.27 1.27) (thickness 0.15)) (justify left bottom) hide)
    )
    (pin "1")
    (pin "2")
    (pin "3")
    (instances
      (project "data-center-rdimm-ddr4-tester"
        (path ""
          (reference "D3") (unit 1)
        )
      )
    )
  )

  (symbol (lib_id "antmicropower:GND") (at 117.475 235.585 90) (unit 1)
    (in_bom yes) (on_board yes) (dnp no) (fields_autoplaced)
    (property "Reference" "#PWR0170" (at 123.825 235.585 0)
      (effects (font (size 1.27 1.27)) hide)
    )
    (property "Value" "GND" (at 120.65 235.5849 90)
      (effects (font (size 1.27 1.27)) (justify right))
    )
    (property "Footprint" "" (at 117.475 235.585 0)
      (effects (font (size 1.27 1.27)) hide)
    )
    (property "Datasheet" "" (at 117.475 235.585 0)
      (effects (font (size 1.27 1.27)) hide)
    )
    (property "Author" "Antmicro" (at 125.095 226.695 0)
      (effects (font (size 1.27 1.27) (thickness 0.15)) (justify left bottom) hide)
    )
    (property "License" "Apache-2.0" (at 127.635 226.695 0)
      (effects (font (size 1.27 1.27) (thickness 0.15)) (justify left bottom) hide)
    )
    (pin "1")
    (instances
      (project "data-center-rdimm-ddr4-tester"
        (path ""
          (reference "#PWR0170") (unit 1)
        )
      )
    )
  )

  (symbol (lib_id "antmicroResistors0402:R_330R_0402") (at 93.345 235.585 0) (unit 1)
    (in_bom yes) (on_board yes) (dnp no)
    (property "Reference" "R54" (at 95.885 238.76 0)
      (effects (font (size 1.524 1.524)))
    )
    (property "Value" "R_330R_0402" (at 113.665 248.285 0)
      (effects (font (size 1.27 1.27) (thickness 0.15)) (justify left bottom) hide)
    )
    (property "Footprint" "antmicro-footprints:R_0402_1005Metric" (at 113.665 250.825 0)
      (effects (font (size 1.27 1.27) (thickness 0.15)) (justify left bottom) hide)
    )
    (property "Datasheet" "https://www.bourns.com/docs/product-datasheets/cr.pdf" (at 113.665 253.365 0)
      (effects (font (size 1.27 1.27) (thickness 0.15)) (justify left bottom) hide)
    )
    (property "Manufacturer" "Bourns" (at 113.665 258.445 0)
      (effects (font (size 1.27 1.27) (thickness 0.15)) (justify left bottom) hide)
    )
    (property "MPN" "CR0402-FX-3300GLF" (at 113.665 255.905 0)
      (effects (font (size 1.27 1.27) (thickness 0.15)) (justify left bottom) hide)
    )
    (property "Val" "330R" (at 95.885 241.3 0)
      (effects (font (size 1.27 1.27) (thickness 0.15)))
    )
    (property "License" "Apache-2.0" (at 113.665 260.985 0)
      (effects (font (size 1.27 1.27) (thickness 0.15)) (justify left bottom) hide)
    )
    (property "Author" "Antmicro" (at 113.665 263.525 0)
      (effects (font (size 1.27 1.27) (thickness 0.15)) (justify left bottom) hide)
    )
    (property "Tolerance" "1%" (at 113.665 245.745 0)
      (effects (font (size 1.27 1.27)) (justify left bottom) hide)
    )
    (pin "1")
    (pin "2")
    (instances
      (project "data-center-rdimm-ddr4-tester"
        (path ""
          (reference "R54") (unit 1)
        )
      )
    )
  )

  (symbol (lib_id "antmicroLEDIndicationDiscrete:LED_G_0603_KP-1608CGCK") (at 83.185 235.585 0) (unit 1)
    (in_bom yes) (on_board yes) (dnp no) (fields_autoplaced)
    (property "Reference" "D9" (at 86.995 227.33 0)
      (effects (font (size 1.524 1.524)))
    )
    (property "Value" "LED_G_0603_KP-1608CGCK" (at 86.995 231.14 0)
      (effects (font (size 1.27 1.27) (thickness 0.15)) hide)
    )
    (property "Footprint" "antmicro-footprints:LED_0603_1608Metric_G" (at 106.045 245.745 0)
      (effects (font (size 1.27 1.27) (thickness 0.15)) (justify left bottom) hide)
    )
    (property "Datasheet" "http://www.farnell.com/datasheets/2045956.pdf" (at 106.045 248.285 0)
      (effects (font (size 1.27 1.27) (thickness 0.15)) (justify left bottom) hide)
    )
    (property "MPN" "KP-1608CGCK" (at 86.995 231.14 0)
      (effects (font (size 1.27 1.27) (thickness 0.15)))
    )
    (property "Manufacturer" "Kingbright" (at 106.045 253.365 0)
      (effects (font (size 1.27 1.27) (thickness 0.15)) (justify left bottom) hide)
    )
    (property "Author" "Antmicro" (at 106.045 255.905 0)
      (effects (font (size 1.27 1.27) (thickness 0.15)) (justify left bottom) hide)
    )
    (property "License" "Apache-2.0" (at 106.045 258.445 0)
      (effects (font (size 1.27 1.27) (thickness 0.15)) (justify left bottom) hide)
    )
    (pin "1")
    (pin "2")
    (instances
      (project "data-center-rdimm-ddr4-tester"
        (path ""
          (reference "D9") (unit 1)
        )
      )
    )
  )

  (symbol (lib_id "antmicropower:GND") (at 222.885 184.785 0) (unit 1)
    (in_bom yes) (on_board yes) (dnp no) (fields_autoplaced)
    (property "Reference" "#PWR0228" (at 222.885 191.135 0)
      (effects (font (size 1.27 1.27)) hide)
    )
    (property "Value" "GND" (at 222.885 189.865 0)
      (effects (font (size 1.27 1.27)))
    )
    (property "Footprint" "" (at 222.885 184.785 0)
      (effects (font (size 1.27 1.27)) hide)
    )
    (property "Datasheet" "" (at 222.885 184.785 0)
      (effects (font (size 1.27 1.27)) hide)
    )
    (property "Author" "Antmicro" (at 231.775 192.405 0)
      (effects (font (size 1.27 1.27) (thickness 0.15)) (justify left bottom) hide)
    )
    (property "License" "Apache-2.0" (at 231.775 194.945 0)
      (effects (font (size 1.27 1.27) (thickness 0.15)) (justify left bottom) hide)
    )
    (pin "1")
    (instances
      (project "data-center-rdimm-ddr4-tester"
        (path ""
          (reference "#PWR0228") (unit 1)
        )
      )
    )
  )

  (symbol (lib_id "antmicropower:GND") (at 62.23 255.27 90) (unit 1)
    (in_bom yes) (on_board yes) (dnp no) (fields_autoplaced)
    (property "Reference" "#PWR0171" (at 68.58 255.27 0)
      (effects (font (size 1.27 1.27)) hide)
    )
    (property "Value" "GND" (at 66.04 255.2699 90)
      (effects (font (size 1.27 1.27)) (justify right))
    )
    (property "Footprint" "" (at 62.23 255.27 0)
      (effects (font (size 1.27 1.27)) hide)
    )
    (property "Datasheet" "" (at 62.23 255.27 0)
      (effects (font (size 1.27 1.27)) hide)
    )
    (property "Author" "Antmicro" (at 69.85 246.38 0)
      (effects (font (size 1.27 1.27) (thickness 0.15)) (justify left bottom) hide)
    )
    (property "License" "Apache-2.0" (at 72.39 246.38 0)
      (effects (font (size 1.27 1.27) (thickness 0.15)) (justify left bottom) hide)
    )
    (pin "1")
    (instances
      (project "data-center-rdimm-ddr4-tester"
        (path ""
          (reference "#PWR0171") (unit 1)
        )
      )
    )
  )

  (symbol (lib_id "antmicroResistors0402:R_330R_0402") (at 38.1 255.27 0) (unit 1)
    (in_bom yes) (on_board yes) (dnp no)
    (property "Reference" "R51" (at 40.64 258.445 0)
      (effects (font (size 1.524 1.524)))
    )
    (property "Value" "R_330R_0402" (at 58.42 267.97 0)
      (effects (font (size 1.27 1.27) (thickness 0.15)) (justify left bottom) hide)
    )
    (property "Footprint" "antmicro-footprints:R_0402_1005Metric" (at 58.42 270.51 0)
      (effects (font (size 1.27 1.27) (thickness 0.15)) (justify left bottom) hide)
    )
    (property "Datasheet" "https://www.bourns.com/docs/product-datasheets/cr.pdf" (at 58.42 273.05 0)
      (effects (font (size 1.27 1.27) (thickness 0.15)) (justify left bottom) hide)
    )
    (property "Manufacturer" "Bourns" (at 58.42 278.13 0)
      (effects (font (size 1.27 1.27) (thickness 0.15)) (justify left bottom) hide)
    )
    (property "MPN" "CR0402-FX-3300GLF" (at 58.42 275.59 0)
      (effects (font (size 1.27 1.27) (thickness 0.15)) (justify left bottom) hide)
    )
    (property "Val" "330R" (at 40.64 260.985 0)
      (effects (font (size 1.27 1.27) (thickness 0.15)))
    )
    (property "License" "Apache-2.0" (at 58.42 280.67 0)
      (effects (font (size 1.27 1.27) (thickness 0.15)) (justify left bottom) hide)
    )
    (property "Author" "Antmicro" (at 58.42 283.21 0)
      (effects (font (size 1.27 1.27) (thickness 0.15)) (justify left bottom) hide)
    )
    (property "Tolerance" "1%" (at 58.42 265.43 0)
      (effects (font (size 1.27 1.27)) (justify left bottom) hide)
    )
    (pin "1")
    (pin "2")
    (instances
      (project "data-center-rdimm-ddr4-tester"
        (path ""
          (reference "R51") (unit 1)
        )
      )
    )
  )

  (symbol (lib_id "antmicroLEDIndicationDiscrete:LED_G_0603_KP-1608CGCK") (at 27.94 255.27 0) (unit 1)
    (in_bom yes) (on_board yes) (dnp no) (fields_autoplaced)
    (property "Reference" "D6" (at 31.75 247.65 0)
      (effects (font (size 1.524 1.524)))
    )
    (property "Value" "LED_G_0603_KP-1608CGCK" (at 31.75 250.19 0)
      (effects (font (size 1.27 1.27) (thickness 0.15)) hide)
    )
    (property "Footprint" "antmicro-footprints:LED_0603_1608Metric_G" (at 50.8 265.43 0)
      (effects (font (size 1.27 1.27) (thickness 0.15)) (justify left bottom) hide)
    )
    (property "Datasheet" "http://www.farnell.com/datasheets/2045956.pdf" (at 50.8 267.97 0)
      (effects (font (size 1.27 1.27) (thickness 0.15)) (justify left bottom) hide)
    )
    (property "MPN" "KP-1608CGCK" (at 31.75 250.19 0)
      (effects (font (size 1.27 1.27) (thickness 0.15)))
    )
    (property "Manufacturer" "Kingbright" (at 50.8 273.05 0)
      (effects (font (size 1.27 1.27) (thickness 0.15)) (justify left bottom) hide)
    )
    (property "Author" "Antmicro" (at 50.8 275.59 0)
      (effects (font (size 1.27 1.27) (thickness 0.15)) (justify left bottom) hide)
    )
    (property "License" "Apache-2.0" (at 50.8 278.13 0)
      (effects (font (size 1.27 1.27) (thickness 0.15)) (justify left bottom) hide)
    )
    (pin "1")
    (pin "2")
    (instances
      (project "data-center-rdimm-ddr4-tester"
        (path ""
          (reference "D6") (unit 1)
        )
      )
    )
  )

  (symbol (lib_id "antmicroResistors0402:R_22R_0402") (at 131.445 85.09 0) (unit 1)
    (in_bom yes) (on_board yes) (dnp no)
    (property "Reference" "R5" (at 130.175 83.82 0)
      (effects (font (size 1.524 1.524)))
    )
    (property "Value" "R_22R_0402" (at 151.765 97.79 0)
      (effects (font (size 1.27 1.27) (thickness 0.15)) (justify left bottom) hide)
    )
    (property "Footprint" "antmicro-footprints:R_0402_1005Metric" (at 151.765 100.33 0)
      (effects (font (size 1.27 1.27) (thickness 0.15)) (justify left bottom) hide)
    )
    (property "Datasheet" "https://www.bourns.com/docs/product-datasheets/cr.pdf" (at 151.765 102.87 0)
      (effects (font (size 1.27 1.27) (thickness 0.15)) (justify left bottom) hide)
    )
    (property "Manufacturer" "Bourns" (at 151.765 107.95 0)
      (effects (font (size 1.27 1.27) (thickness 0.15)) (justify left bottom) hide)
    )
    (property "MPN" "CR0402-FX-22R0GLF" (at 151.765 105.41 0)
      (effects (font (size 1.27 1.27) (thickness 0.15)) (justify left bottom) hide)
    )
    (property "Val" "22R" (at 138.43 83.82 0)
      (effects (font (size 1.27 1.27) (thickness 0.15)))
    )
    (property "License" "Apache-2.0" (at 151.765 110.49 0)
      (effects (font (size 1.27 1.27) (thickness 0.15)) (justify left bottom) hide)
    )
    (property "Author" "Antmicro" (at 151.765 113.03 0)
      (effects (font (size 1.27 1.27) (thickness 0.15)) (justify left bottom) hide)
    )
    (property "Tolerance" "1%" (at 151.765 95.25 0)
      (effects (font (size 1.27 1.27)) (justify left bottom) hide)
    )
    (pin "1")
    (pin "2")
    (instances
      (project "data-center-rdimm-ddr4-tester"
        (path ""
          (reference "R5") (unit 1)
        )
      )
    )
  )

  (symbol (lib_id "antmicroVideoConnectors:HDMI-A_WE_685119134923") (at 210.82 39.37 0) (unit 1)
    (in_bom yes) (on_board yes) (dnp no)
    (property "Reference" "J6" (at 223.52 34.925 0)
      (effects (font (size 1.524 1.524)))
    )
    (property "Value" "HDMI_A_Female_685119134923" (at 243.84 40.64 0)
      (effects (font (size 1.27 1.27) (thickness 0.15)) (justify left bottom) hide)
    )
    (property "Footprint" "antmicro-footprints:HDMI-A_Receptacle_WE_685119134923" (at 246.38 46.99 0)
      (effects (font (size 1.27 1.27) (thickness 0.15)) (justify left bottom) hide)
    )
    (property "Datasheet" "https://www.we-online.com/components/products/datasheet/685119134923.pdf" (at 246.38 49.53 0)
      (effects (font (size 1.27 1.27) (thickness 0.15)) (justify left bottom) hide)
    )
    (property "MPN" "685119134923" (at 213.36 95.25 0)
      (effects (font (size 1.27 1.27) (thickness 0.15)) (justify left bottom))
    )
    (property "Manufacturer" "Würth Elektronik" (at 234.95 41.91 0)
      (effects (font (size 1.27 1.27) (thickness 0.15)) (justify left bottom) hide)
    )
    (property "License" "Apache-2.0" (at 246.38 59.69 0)
      (effects (font (size 1.27 1.27) (thickness 0.15)) (justify left bottom) hide)
    )
    (property "Author" "Antmicro" (at 246.38 57.15 0)
      (effects (font (size 1.27 1.27) (thickness 0.15)) (justify left bottom) hide)
    )
    (pin "1")
    (pin "10")
    (pin "11")
    (pin "12")
    (pin "13")
    (pin "14")
    (pin "15")
    (pin "16")
    (pin "17")
    (pin "18")
    (pin "19")
    (pin "2")
    (pin "3")
    (pin "4")
    (pin "5")
    (pin "6")
    (pin "7")
    (pin "8")
    (pin "9")
    (pin "SH")
    (instances
      (project "data-center-rdimm-ddr4-tester"
        (path ""
          (reference "J6") (unit 1)
        )
      )
    )
  )

  (symbol (lib_id "antmicroResistors0402:R_22R_0402") (at 131.445 50.8 0) (unit 1)
    (in_bom yes) (on_board yes) (dnp no)
    (property "Reference" "R18" (at 129.54 49.53 0)
      (effects (font (size 1.524 1.524)))
    )
    (property "Value" "R_22R_0402" (at 151.765 63.5 0)
      (effects (font (size 1.27 1.27) (thickness 0.15)) (justify left bottom) hide)
    )
    (property "Footprint" "antmicro-footprints:R_0402_1005Metric" (at 151.765 66.04 0)
      (effects (font (size 1.27 1.27) (thickness 0.15)) (justify left bottom) hide)
    )
    (property "Datasheet" "https://www.bourns.com/docs/product-datasheets/cr.pdf" (at 151.765 68.58 0)
      (effects (font (size 1.27 1.27) (thickness 0.15)) (justify left bottom) hide)
    )
    (property "Manufacturer" "Bourns" (at 151.765 73.66 0)
      (effects (font (size 1.27 1.27) (thickness 0.15)) (justify left bottom) hide)
    )
    (property "MPN" "CR0402-FX-22R0GLF" (at 151.765 71.12 0)
      (effects (font (size 1.27 1.27) (thickness 0.15)) (justify left bottom) hide)
    )
    (property "Val" "22R" (at 138.43 49.53 0)
      (effects (font (size 1.27 1.27) (thickness 0.15)))
    )
    (property "License" "Apache-2.0" (at 151.765 76.2 0)
      (effects (font (size 1.27 1.27) (thickness 0.15)) (justify left bottom) hide)
    )
    (property "Author" "Antmicro" (at 151.765 78.74 0)
      (effects (font (size 1.27 1.27) (thickness 0.15)) (justify left bottom) hide)
    )
    (property "Tolerance" "1%" (at 151.765 60.96 0)
      (effects (font (size 1.27 1.27)) (justify left bottom) hide)
    )
    (pin "1")
    (pin "2")
    (instances
      (project "data-center-rdimm-ddr4-tester"
        (path ""
          (reference "R18") (unit 1)
        )
      )
    )
  )

  (symbol (lib_id "antmicroResistors0402:R_22R_0402") (at 131.445 53.34 0) (unit 1)
    (in_bom yes) (on_board yes) (dnp no)
    (property "Reference" "R19" (at 129.54 52.07 0)
      (effects (font (size 1.524 1.524)))
    )
    (property "Value" "R_22R_0402" (at 151.765 66.04 0)
      (effects (font (size 1.27 1.27) (thickness 0.15)) (justify left bottom) hide)
    )
    (property "Footprint" "antmicro-footprints:R_0402_1005Metric" (at 151.765 68.58 0)
      (effects (font (size 1.27 1.27) (thickness 0.15)) (justify left bottom) hide)
    )
    (property "Datasheet" "https://www.bourns.com/docs/product-datasheets/cr.pdf" (at 151.765 71.12 0)
      (effects (font (size 1.27 1.27) (thickness 0.15)) (justify left bottom) hide)
    )
    (property "Manufacturer" "Bourns" (at 151.765 76.2 0)
      (effects (font (size 1.27 1.27) (thickness 0.15)) (justify left bottom) hide)
    )
    (property "MPN" "CR0402-FX-22R0GLF" (at 151.765 73.66 0)
      (effects (font (size 1.27 1.27) (thickness 0.15)) (justify left bottom) hide)
    )
    (property "Val" "22R" (at 138.43 52.07 0)
      (effects (font (size 1.27 1.27) (thickness 0.15)))
    )
    (property "License" "Apache-2.0" (at 151.765 78.74 0)
      (effects (font (size 1.27 1.27) (thickness 0.15)) (justify left bottom) hide)
    )
    (property "Author" "Antmicro" (at 151.765 81.28 0)
      (effects (font (size 1.27 1.27) (thickness 0.15)) (justify left bottom) hide)
    )
    (property "Tolerance" "1%" (at 151.765 63.5 0)
      (effects (font (size 1.27 1.27)) (justify left bottom) hide)
    )
    (pin "1")
    (pin "2")
    (instances
      (project "data-center-rdimm-ddr4-tester"
        (path ""
          (reference "R19") (unit 1)
        )
      )
    )
  )

  (symbol (lib_id "antmicroResistors0402:R_22R_0402") (at 131.445 55.88 0) (unit 1)
    (in_bom yes) (on_board yes) (dnp no)
    (property "Reference" "R20" (at 129.54 54.61 0)
      (effects (font (size 1.524 1.524)))
    )
    (property "Value" "R_22R_0402" (at 151.765 68.58 0)
      (effects (font (size 1.27 1.27) (thickness 0.15)) (justify left bottom) hide)
    )
    (property "Footprint" "antmicro-footprints:R_0402_1005Metric" (at 151.765 71.12 0)
      (effects (font (size 1.27 1.27) (thickness 0.15)) (justify left bottom) hide)
    )
    (property "Datasheet" "https://www.bourns.com/docs/product-datasheets/cr.pdf" (at 151.765 73.66 0)
      (effects (font (size 1.27 1.27) (thickness 0.15)) (justify left bottom) hide)
    )
    (property "Manufacturer" "Bourns" (at 151.765 78.74 0)
      (effects (font (size 1.27 1.27) (thickness 0.15)) (justify left bottom) hide)
    )
    (property "MPN" "CR0402-FX-22R0GLF" (at 151.765 76.2 0)
      (effects (font (size 1.27 1.27) (thickness 0.15)) (justify left bottom) hide)
    )
    (property "Val" "22R" (at 138.43 54.61 0)
      (effects (font (size 1.27 1.27) (thickness 0.15)))
    )
    (property "License" "Apache-2.0" (at 151.765 81.28 0)
      (effects (font (size 1.27 1.27) (thickness 0.15)) (justify left bottom) hide)
    )
    (property "Author" "Antmicro" (at 151.765 83.82 0)
      (effects (font (size 1.27 1.27) (thickness 0.15)) (justify left bottom) hide)
    )
    (property "Tolerance" "1%" (at 151.765 66.04 0)
      (effects (font (size 1.27 1.27)) (justify left bottom) hide)
    )
    (pin "1")
    (pin "2")
    (instances
      (project "data-center-rdimm-ddr4-tester"
        (path ""
          (reference "R20") (unit 1)
        )
      )
    )
  )

  (symbol (lib_id "antmicroResistors0402:R_22R_0402") (at 131.445 58.42 0) (unit 1)
    (in_bom yes) (on_board yes) (dnp no)
    (property "Reference" "R25" (at 129.54 57.15 0)
      (effects (font (size 1.524 1.524)))
    )
    (property "Value" "R_22R_0402" (at 151.765 71.12 0)
      (effects (font (size 1.27 1.27) (thickness 0.15)) (justify left bottom) hide)
    )
    (property "Footprint" "antmicro-footprints:R_0402_1005Metric" (at 151.765 73.66 0)
      (effects (font (size 1.27 1.27) (thickness 0.15)) (justify left bottom) hide)
    )
    (property "Datasheet" "https://www.bourns.com/docs/product-datasheets/cr.pdf" (at 151.765 76.2 0)
      (effects (font (size 1.27 1.27) (thickness 0.15)) (justify left bottom) hide)
    )
    (property "Manufacturer" "Bourns" (at 151.765 81.28 0)
      (effects (font (size 1.27 1.27) (thickness 0.15)) (justify left bottom) hide)
    )
    (property "MPN" "CR0402-FX-22R0GLF" (at 151.765 78.74 0)
      (effects (font (size 1.27 1.27) (thickness 0.15)) (justify left bottom) hide)
    )
    (property "Val" "22R" (at 138.43 57.15 0)
      (effects (font (size 1.27 1.27) (thickness 0.15)))
    )
    (property "License" "Apache-2.0" (at 151.765 83.82 0)
      (effects (font (size 1.27 1.27) (thickness 0.15)) (justify left bottom) hide)
    )
    (property "Author" "Antmicro" (at 151.765 86.36 0)
      (effects (font (size 1.27 1.27) (thickness 0.15)) (justify left bottom) hide)
    )
    (property "Tolerance" "1%" (at 151.765 68.58 0)
      (effects (font (size 1.27 1.27)) (justify left bottom) hide)
    )
    (pin "1")
    (pin "2")
    (instances
      (project "data-center-rdimm-ddr4-tester"
        (path ""
          (reference "R25") (unit 1)
        )
      )
    )
  )

  (symbol (lib_id "antmicropower:GND") (at 243.84 92.71 0) (unit 1)
    (in_bom yes) (on_board yes) (dnp no) (fields_autoplaced)
    (property "Reference" "#PWR0233" (at 243.84 99.06 0)
      (effects (font (size 1.27 1.27)) hide)
    )
    (property "Value" "GND" (at 243.84 97.155 0)
      (effects (font (size 1.27 1.27)))
    )
    (property "Footprint" "" (at 243.84 92.71 0)
      (effects (font (size 1.27 1.27)) hide)
    )
    (property "Datasheet" "" (at 243.84 92.71 0)
      (effects (font (size 1.27 1.27)) hide)
    )
    (property "Author" "Antmicro" (at 252.73 100.33 0)
      (effects (font (size 1.27 1.27) (thickness 0.15)) (justify left bottom) hide)
    )
    (property "License" "Apache-2.0" (at 252.73 102.87 0)
      (effects (font (size 1.27 1.27) (thickness 0.15)) (justify left bottom) hide)
    )
    (pin "1")
    (instances
      (project "data-center-rdimm-ddr4-tester"
        (path ""
          (reference "#PWR0233") (unit 1)
        )
      )
    )
  )

  (symbol (lib_id "antmicroTestPoints:TP_1mm_SMD") (at 204.47 77.47 180) (unit 1)
    (in_bom yes) (on_board yes) (dnp no) (fields_autoplaced)
    (property "Reference" "TP1" (at 199.39 77.4699 0)
      (effects (font (size 1.27 1.27)) (justify left))
    )
    (property "Value" "TP_1mm_SMD" (at 189.23 69.85 0)
      (effects (font (size 1.27 1.27) (thickness 0.15)) (justify left bottom) hide)
    )
    (property "Footprint" "antmicro-footprints:TP_SMD_1mm" (at 189.23 67.31 0)
      (effects (font (size 1.27 1.27) (thickness 0.15)) (justify left bottom) hide)
    )
    (property "Datasheet" "" (at 189.23 64.77 0)
      (effects (font (size 1.27 1.27) (thickness 0.15)) (justify left bottom) hide)
    )
    (property "MPN" "" (at 204.47 77.47 0)
      (effects (font (size 1.27 1.27)) hide)
    )
    (property "Manufacturer" "" (at 204.47 77.47 0)
      (effects (font (size 1.27 1.27)) hide)
    )
    (property "Author" "Antmicro" (at 189.23 62.23 0)
      (effects (font (size 1.27 1.27) (thickness 0.15)) (justify left bottom) hide)
    )
    (property "License" "Apache-2.0" (at 189.23 59.69 0)
      (effects (font (size 1.27 1.27) (thickness 0.15)) (justify left bottom) hide)
    )
    (pin "1")
    (instances
      (project "data-center-rdimm-ddr4-tester"
        (path ""
          (reference "TP1") (unit 1)
        )
      )
    )
  )

  (symbol (lib_id "antmicroTestPoints:TP_1mm_SMD") (at 204.47 69.85 180) (unit 1)
    (in_bom yes) (on_board yes) (dnp no) (fields_autoplaced)
    (property "Reference" "TP2" (at 199.39 69.8499 0)
      (effects (font (size 1.27 1.27)) (justify left))
    )
    (property "Value" "TP_1mm_SMD" (at 189.23 62.23 0)
      (effects (font (size 1.27 1.27) (thickness 0.15)) (justify left bottom) hide)
    )
    (property "Footprint" "antmicro-footprints:TP_SMD_1mm" (at 189.23 59.69 0)
      (effects (font (size 1.27 1.27) (thickness 0.15)) (justify left bottom) hide)
    )
    (property "Datasheet" "" (at 189.23 57.15 0)
      (effects (font (size 1.27 1.27) (thickness 0.15)) (justify left bottom) hide)
    )
    (property "MPN" "" (at 204.47 69.85 0)
      (effects (font (size 1.27 1.27)) hide)
    )
    (property "Manufacturer" "" (at 204.47 69.85 0)
      (effects (font (size 1.27 1.27)) hide)
    )
    (property "Author" "Antmicro" (at 189.23 54.61 0)
      (effects (font (size 1.27 1.27) (thickness 0.15)) (justify left bottom) hide)
    )
    (property "License" "Apache-2.0" (at 189.23 52.07 0)
      (effects (font (size 1.27 1.27) (thickness 0.15)) (justify left bottom) hide)
    )
    (pin "1")
    (instances
      (project "data-center-rdimm-ddr4-tester"
        (path ""
          (reference "TP2") (unit 1)
        )
      )
    )
  )

  (symbol (lib_id "antmicroTestPoints:TP_1mm_SMD") (at 204.47 82.55 180) (unit 1)
    (in_bom yes) (on_board yes) (dnp no)
    (property "Reference" "TP3" (at 197.485 82.55 0)
      (effects (font (size 1.27 1.27)))
    )
    (property "Value" "TP_1mm_SMD" (at 189.23 74.93 0)
      (effects (font (size 1.27 1.27) (thickness 0.15)) (justify left bottom) hide)
    )
    (property "Footprint" "antmicro-footprints:TP_SMD_1mm" (at 189.23 72.39 0)
      (effects (font (size 1.27 1.27) (thickness 0.15)) (justify left bottom) hide)
    )
    (property "Datasheet" "" (at 189.23 69.85 0)
      (effects (font (size 1.27 1.27) (thickness 0.15)) (justify left bottom) hide)
    )
    (property "MPN" "" (at 204.47 82.55 0)
      (effects (font (size 1.27 1.27)) hide)
    )
    (property "Manufacturer" "" (at 204.47 82.55 0)
      (effects (font (size 1.27 1.27)) hide)
    )
    (property "Author" "Antmicro" (at 189.23 67.31 0)
      (effects (font (size 1.27 1.27) (thickness 0.15)) (justify left bottom) hide)
    )
    (property "License" "Apache-2.0" (at 189.23 64.77 0)
      (effects (font (size 1.27 1.27) (thickness 0.15)) (justify left bottom) hide)
    )
    (pin "1")
    (instances
      (project "data-center-rdimm-ddr4-tester"
        (path ""
          (reference "TP3") (unit 1)
        )
      )
    )
  )

  (symbol (lib_id "antmicroTestPoints:TP_1mm_SMD") (at 204.47 72.39 0) (mirror y) (unit 1)
    (in_bom yes) (on_board yes) (dnp no)
    (property "Reference" "TP4" (at 199.39 72.39 0)
      (effects (font (size 1.27 1.27)) (justify left))
    )
    (property "Value" "TP_1mm_SMD" (at 189.23 80.01 0)
      (effects (font (size 1.27 1.27) (thickness 0.15)) (justify left bottom) hide)
    )
    (property "Footprint" "antmicro-footprints:TP_SMD_1mm" (at 189.23 82.55 0)
      (effects (font (size 1.27 1.27) (thickness 0.15)) (justify left bottom) hide)
    )
    (property "Datasheet" "" (at 189.23 85.09 0)
      (effects (font (size 1.27 1.27) (thickness 0.15)) (justify left bottom) hide)
    )
    (property "MPN" "" (at 204.47 72.39 0)
      (effects (font (size 1.27 1.27)) hide)
    )
    (property "Manufacturer" "" (at 204.47 72.39 0)
      (effects (font (size 1.27 1.27)) hide)
    )
    (property "Author" "Antmicro" (at 189.23 87.63 0)
      (effects (font (size 1.27 1.27) (thickness 0.15)) (justify left bottom) hide)
    )
    (property "License" "Apache-2.0" (at 189.23 90.17 0)
      (effects (font (size 1.27 1.27) (thickness 0.15)) (justify left bottom) hide)
    )
    (pin "1")
    (instances
      (project "data-center-rdimm-ddr4-tester"
        (path ""
          (reference "TP4") (unit 1)
        )
      )
    )
  )

  (symbol (lib_id "antmicroTestPoints:TP_1mm_SMD") (at 204.47 90.17 0) (mirror y) (unit 1)
    (in_bom yes) (on_board yes) (dnp no)
    (property "Reference" "TP5" (at 199.39 90.17 0)
      (effects (font (size 1.27 1.27)) (justify left))
    )
    (property "Value" "TP_1mm_SMD" (at 189.23 97.79 0)
      (effects (font (size 1.27 1.27) (thickness 0.15)) (justify left bottom) hide)
    )
    (property "Footprint" "antmicro-footprints:TP_SMD_1mm" (at 189.23 100.33 0)
      (effects (font (size 1.27 1.27) (thickness 0.15)) (justify left bottom) hide)
    )
    (property "Datasheet" "" (at 189.23 102.87 0)
      (effects (font (size 1.27 1.27) (thickness 0.15)) (justify left bottom) hide)
    )
    (property "MPN" "" (at 204.47 90.17 0)
      (effects (font (size 1.27 1.27)) hide)
    )
    (property "Manufacturer" "" (at 204.47 90.17 0)
      (effects (font (size 1.27 1.27)) hide)
    )
    (property "Author" "Antmicro" (at 189.23 105.41 0)
      (effects (font (size 1.27 1.27) (thickness 0.15)) (justify left bottom) hide)
    )
    (property "License" "Apache-2.0" (at 189.23 107.95 0)
      (effects (font (size 1.27 1.27) (thickness 0.15)) (justify left bottom) hide)
    )
    (pin "1")
    (instances
      (project "data-center-rdimm-ddr4-tester"
        (path ""
          (reference "TP5") (unit 1)
        )
      )
    )
  )

  (symbol (lib_id "antmicroTVSDiodes:TPD8S009DSMR") (at 277.495 57.785 0) (mirror y) (unit 1)
    (in_bom yes) (on_board yes) (dnp no) (fields_autoplaced)
    (property "Reference" "IC3" (at 269.24 49.53 0)
      (effects (font (size 1.27 1.27)))
    )
    (property "Value" "TPD8S009DSMR" (at 269.24 52.07 0)
      (effects (font (size 1.27 1.27) (thickness 0.15)))
    )
    (property "Footprint" "antmicro-footprints:R-PDSO-N15" (at 247.015 65.405 0)
      (effects (font (size 1.27 1.27) (thickness 0.15)) (justify left bottom) hide)
    )
    (property "Datasheet" "https://www.ti.com/lit/ds/symlink/tpd8s009.pdf?ts=1679406571326&ref_url=https%253A%252F%252Fwww.ti.com%252Fproduct%252FTPD8S009%252Fpart-details%252FTPD8S009DSMR" (at 247.015 67.945 0)
      (effects (font (size 1.27 1.27) (thickness 0.15)) (justify left bottom) hide)
    )
    (property "MPN" "TPD8S009DSMR" (at 247.015 70.485 0)
      (effects (font (size 1.27 1.27) (thickness 0.15)) (justify left bottom) hide)
    )
    (property "Manufacturer" "Texas Instruments" (at 247.015 73.025 0)
      (effects (font (size 1.27 1.27) (thickness 0.15)) (justify left bottom) hide)
    )
    (property "Author" "Antmicro" (at 247.015 75.565 0)
      (effects (font (size 1.27 1.27) (thickness 0.15)) (justify left bottom) hide)
    )
    (property "License" "Apache-2.0" (at 247.015 78.105 0)
      (effects (font (size 1.27 1.27) (thickness 0.15)) (justify left bottom) hide)
    )
    (pin "1")
    (pin "10")
    (pin "11")
    (pin "12")
    (pin "13")
    (pin "14")
    (pin "15")
    (pin "2")
    (pin "3")
    (pin "4")
    (pin "5")
    (pin "6")
    (pin "7")
    (pin "8")
    (pin "9")
    (pin "8")
    (instances
      (project "data-center-rdimm-ddr4-tester"
        (path ""
          (reference "IC3") (unit 1)
        )
      )
    )
  )

  (symbol (lib_id "antmicroResistors0402:R_0R_0402") (at 281.305 46.355 270) (unit 1)
    (in_bom yes) (on_board yes) (dnp no) (fields_autoplaced)
    (property "Reference" "R139" (at 283.21 47.625 90)
      (effects (font (size 1.524 1.524)) (justify left))
    )
    (property "Value" "R_0R_0402" (at 268.605 66.675 0)
      (effects (font (size 1.27 1.27) (thickness 0.15)) (justify left bottom) hide)
    )
    (property "Footprint" "antmicro-footprints:R_0402_1005Metric" (at 266.065 66.675 0)
      (effects (font (size 1.27 1.27) (thickness 0.15)) (justify left bottom) hide)
    )
    (property "Datasheet" "https://industrial.panasonic.com/cdbs/www-data/pdf/RDA0000/AOA0000C301.pdf" (at 263.525 66.675 0)
      (effects (font (size 1.27 1.27) (thickness 0.15)) (justify left bottom) hide)
    )
    (property "Manufacturer" "Panasonic" (at 258.445 66.675 0)
      (effects (font (size 1.27 1.27) (thickness 0.15)) (justify left bottom) hide)
    )
    (property "MPN" "ERJ2GE0R00X" (at 260.985 66.675 0)
      (effects (font (size 1.27 1.27) (thickness 0.15)) (justify left bottom) hide)
    )
    (property "Val" "0R" (at 283.21 50.7999 90)
      (effects (font (size 1.27 1.27) (thickness 0.15)) (justify left))
    )
    (property "License" "Apache-2.0" (at 255.905 66.675 0)
      (effects (font (size 1.27 1.27) (thickness 0.15)) (justify left bottom) hide)
    )
    (property "Author" "Antmicro" (at 253.365 66.675 0)
      (effects (font (size 1.27 1.27) (thickness 0.15)) (justify left bottom) hide)
    )
    (property "Tolerance" "~" (at 271.145 66.675 0)
      (effects (font (size 1.27 1.27)) (justify left bottom) hide)
    )
    (property "Current" "1A" (at 250.825 66.675 0)
      (effects (font (size 1.27 1.27) (thickness 0.15)) (justify left bottom) hide)
    )
    (pin "1")
    (pin "2")
    (instances
      (project "data-center-rdimm-ddr4-tester"
        (path ""
          (reference "R139") (unit 1)
        )
      )
    )
  )

  (symbol (lib_id "antmicroResistors0402:R_0R_0402") (at 290.83 46.355 270) (unit 1)
    (in_bom yes) (on_board yes) (dnp no) (fields_autoplaced)
    (property "Reference" "R140" (at 293.37 47.625 90)
      (effects (font (size 1.524 1.524)) (justify left))
    )
    (property "Value" "R_0R_0402" (at 278.13 66.675 0)
      (effects (font (size 1.27 1.27) (thickness 0.15)) (justify left bottom) hide)
    )
    (property "Footprint" "antmicro-footprints:R_0402_1005Metric" (at 275.59 66.675 0)
      (effects (font (size 1.27 1.27) (thickness 0.15)) (justify left bottom) hide)
    )
    (property "Datasheet" "https://industrial.panasonic.com/cdbs/www-data/pdf/RDA0000/AOA0000C301.pdf" (at 273.05 66.675 0)
      (effects (font (size 1.27 1.27) (thickness 0.15)) (justify left bottom) hide)
    )
    (property "Manufacturer" "Panasonic" (at 267.97 66.675 0)
      (effects (font (size 1.27 1.27) (thickness 0.15)) (justify left bottom) hide)
    )
    (property "MPN" "ERJ2GE0R00X" (at 270.51 66.675 0)
      (effects (font (size 1.27 1.27) (thickness 0.15)) (justify left bottom) hide)
    )
    (property "Val" "0R" (at 293.37 50.7999 90)
      (effects (font (size 1.27 1.27) (thickness 0.15)) (justify left))
    )
    (property "License" "Apache-2.0" (at 265.43 66.675 0)
      (effects (font (size 1.27 1.27) (thickness 0.15)) (justify left bottom) hide)
    )
    (property "Author" "Antmicro" (at 262.89 66.675 0)
      (effects (font (size 1.27 1.27) (thickness 0.15)) (justify left bottom) hide)
    )
    (property "Tolerance" "~" (at 280.67 66.675 0)
      (effects (font (size 1.27 1.27)) (justify left bottom) hide)
    )
    (property "Current" "1A" (at 260.35 66.675 0)
      (effects (font (size 1.27 1.27) (thickness 0.15)) (justify left bottom) hide)
    )
    (pin "1")
    (pin "2")
    (instances
      (project "data-center-rdimm-ddr4-tester"
        (path ""
          (reference "R140") (unit 1)
        )
      )
    )
  )

  (symbol (lib_id "antmicroResistors0402:R_0R_0402") (at 300.355 46.355 270) (unit 1)
    (in_bom yes) (on_board yes) (dnp no) (fields_autoplaced)
    (property "Reference" "R141" (at 302.26 47.625 90)
      (effects (font (size 1.524 1.524)) (justify left))
    )
    (property "Value" "R_0R_0402" (at 287.655 66.675 0)
      (effects (font (size 1.27 1.27) (thickness 0.15)) (justify left bottom) hide)
    )
    (property "Footprint" "antmicro-footprints:R_0402_1005Metric" (at 285.115 66.675 0)
      (effects (font (size 1.27 1.27) (thickness 0.15)) (justify left bottom) hide)
    )
    (property "Datasheet" "https://industrial.panasonic.com/cdbs/www-data/pdf/RDA0000/AOA0000C301.pdf" (at 282.575 66.675 0)
      (effects (font (size 1.27 1.27) (thickness 0.15)) (justify left bottom) hide)
    )
    (property "Manufacturer" "Panasonic" (at 277.495 66.675 0)
      (effects (font (size 1.27 1.27) (thickness 0.15)) (justify left bottom) hide)
    )
    (property "MPN" "ERJ2GE0R00X" (at 280.035 66.675 0)
      (effects (font (size 1.27 1.27) (thickness 0.15)) (justify left bottom) hide)
    )
    (property "Val" "0R" (at 302.26 50.7999 90)
      (effects (font (size 1.27 1.27) (thickness 0.15)) (justify left))
    )
    (property "License" "Apache-2.0" (at 274.955 66.675 0)
      (effects (font (size 1.27 1.27) (thickness 0.15)) (justify left bottom) hide)
    )
    (property "Author" "Antmicro" (at 272.415 66.675 0)
      (effects (font (size 1.27 1.27) (thickness 0.15)) (justify left bottom) hide)
    )
    (property "Tolerance" "~" (at 290.195 66.675 0)
      (effects (font (size 1.27 1.27)) (justify left bottom) hide)
    )
    (property "Current" "1A" (at 269.875 66.675 0)
      (effects (font (size 1.27 1.27) (thickness 0.15)) (justify left bottom) hide)
    )
    (pin "1")
    (pin "2")
    (instances
      (project "data-center-rdimm-ddr4-tester"
        (path ""
          (reference "R141") (unit 1)
        )
      )
    )
  )

  (symbol (lib_id "antmicroResistors0402:R_0R_0402") (at 309.88 46.355 270) (unit 1)
    (in_bom yes) (on_board yes) (dnp no) (fields_autoplaced)
    (property "Reference" "R142" (at 312.42 47.625 90)
      (effects (font (size 1.524 1.524)) (justify left))
    )
    (property "Value" "R_0R_0402" (at 297.18 66.675 0)
      (effects (font (size 1.27 1.27) (thickness 0.15)) (justify left bottom) hide)
    )
    (property "Footprint" "antmicro-footprints:R_0402_1005Metric" (at 294.64 66.675 0)
      (effects (font (size 1.27 1.27) (thickness 0.15)) (justify left bottom) hide)
    )
    (property "Datasheet" "https://industrial.panasonic.com/cdbs/www-data/pdf/RDA0000/AOA0000C301.pdf" (at 292.1 66.675 0)
      (effects (font (size 1.27 1.27) (thickness 0.15)) (justify left bottom) hide)
    )
    (property "Manufacturer" "Panasonic" (at 287.02 66.675 0)
      (effects (font (size 1.27 1.27) (thickness 0.15)) (justify left bottom) hide)
    )
    (property "MPN" "ERJ2GE0R00X" (at 289.56 66.675 0)
      (effects (font (size 1.27 1.27) (thickness 0.15)) (justify left bottom) hide)
    )
    (property "Val" "0R" (at 312.42 50.7999 90)
      (effects (font (size 1.27 1.27) (thickness 0.15)) (justify left))
    )
    (property "License" "Apache-2.0" (at 284.48 66.675 0)
      (effects (font (size 1.27 1.27) (thickness 0.15)) (justify left bottom) hide)
    )
    (property "Author" "Antmicro" (at 281.94 66.675 0)
      (effects (font (size 1.27 1.27) (thickness 0.15)) (justify left bottom) hide)
    )
    (property "Tolerance" "~" (at 299.72 66.675 0)
      (effects (font (size 1.27 1.27)) (justify left bottom) hide)
    )
    (property "Current" "1A" (at 279.4 66.675 0)
      (effects (font (size 1.27 1.27) (thickness 0.15)) (justify left bottom) hide)
    )
    (pin "1")
    (pin "2")
    (instances
      (project "data-center-rdimm-ddr4-tester"
        (path ""
          (reference "R142") (unit 1)
        )
      )
    )
  )

  (symbol (lib_id "antmicroResistors0402:R_0R_0402") (at 319.405 46.355 270) (unit 1)
    (in_bom yes) (on_board yes) (dnp no) (fields_autoplaced)
    (property "Reference" "R143" (at 321.31 47.625 90)
      (effects (font (size 1.524 1.524)) (justify left))
    )
    (property "Value" "R_0R_0402" (at 306.705 66.675 0)
      (effects (font (size 1.27 1.27) (thickness 0.15)) (justify left bottom) hide)
    )
    (property "Footprint" "antmicro-footprints:R_0402_1005Metric" (at 304.165 66.675 0)
      (effects (font (size 1.27 1.27) (thickness 0.15)) (justify left bottom) hide)
    )
    (property "Datasheet" "https://industrial.panasonic.com/cdbs/www-data/pdf/RDA0000/AOA0000C301.pdf" (at 301.625 66.675 0)
      (effects (font (size 1.27 1.27) (thickness 0.15)) (justify left bottom) hide)
    )
    (property "Manufacturer" "Panasonic" (at 296.545 66.675 0)
      (effects (font (size 1.27 1.27) (thickness 0.15)) (justify left bottom) hide)
    )
    (property "MPN" "ERJ2GE0R00X" (at 299.085 66.675 0)
      (effects (font (size 1.27 1.27) (thickness 0.15)) (justify left bottom) hide)
    )
    (property "Val" "0R" (at 321.31 50.7999 90)
      (effects (font (size 1.27 1.27) (thickness 0.15)) (justify left))
    )
    (property "License" "Apache-2.0" (at 294.005 66.675 0)
      (effects (font (size 1.27 1.27) (thickness 0.15)) (justify left bottom) hide)
    )
    (property "Author" "Antmicro" (at 291.465 66.675 0)
      (effects (font (size 1.27 1.27) (thickness 0.15)) (justify left bottom) hide)
    )
    (property "Tolerance" "~" (at 309.245 66.675 0)
      (effects (font (size 1.27 1.27)) (justify left bottom) hide)
    )
    (property "Current" "1A" (at 288.925 66.675 0)
      (effects (font (size 1.27 1.27) (thickness 0.15)) (justify left bottom) hide)
    )
    (pin "1")
    (pin "2")
    (instances
      (project "data-center-rdimm-ddr4-tester"
        (path ""
          (reference "R143") (unit 1)
        )
      )
    )
  )

  (symbol (lib_id "antmicroResistors0402:R_0R_0402") (at 328.93 46.355 270) (unit 1)
    (in_bom yes) (on_board yes) (dnp no) (fields_autoplaced)
    (property "Reference" "R144" (at 331.47 47.625 90)
      (effects (font (size 1.524 1.524)) (justify left))
    )
    (property "Value" "R_0R_0402" (at 316.23 66.675 0)
      (effects (font (size 1.27 1.27) (thickness 0.15)) (justify left bottom) hide)
    )
    (property "Footprint" "antmicro-footprints:R_0402_1005Metric" (at 313.69 66.675 0)
      (effects (font (size 1.27 1.27) (thickness 0.15)) (justify left bottom) hide)
    )
    (property "Datasheet" "https://industrial.panasonic.com/cdbs/www-data/pdf/RDA0000/AOA0000C301.pdf" (at 311.15 66.675 0)
      (effects (font (size 1.27 1.27) (thickness 0.15)) (justify left bottom) hide)
    )
    (property "Manufacturer" "Panasonic" (at 306.07 66.675 0)
      (effects (font (size 1.27 1.27) (thickness 0.15)) (justify left bottom) hide)
    )
    (property "MPN" "ERJ2GE0R00X" (at 308.61 66.675 0)
      (effects (font (size 1.27 1.27) (thickness 0.15)) (justify left bottom) hide)
    )
    (property "Val" "0R" (at 331.47 50.7999 90)
      (effects (font (size 1.27 1.27) (thickness 0.15)) (justify left))
    )
    (property "License" "Apache-2.0" (at 303.53 66.675 0)
      (effects (font (size 1.27 1.27) (thickness 0.15)) (justify left bottom) hide)
    )
    (property "Author" "Antmicro" (at 300.99 66.675 0)
      (effects (font (size 1.27 1.27) (thickness 0.15)) (justify left bottom) hide)
    )
    (property "Tolerance" "~" (at 318.77 66.675 0)
      (effects (font (size 1.27 1.27)) (justify left bottom) hide)
    )
    (property "Current" "1A" (at 298.45 66.675 0)
      (effects (font (size 1.27 1.27) (thickness 0.15)) (justify left bottom) hide)
    )
    (pin "1")
    (pin "2")
    (instances
      (project "data-center-rdimm-ddr4-tester"
        (path ""
          (reference "R144") (unit 1)
        )
      )
    )
  )

  (symbol (lib_id "antmicroResistors0402:R_0R_0402") (at 338.455 46.355 270) (unit 1)
    (in_bom yes) (on_board yes) (dnp no) (fields_autoplaced)
    (property "Reference" "R145" (at 340.36 47.625 90)
      (effects (font (size 1.524 1.524)) (justify left))
    )
    (property "Value" "R_0R_0402" (at 325.755 66.675 0)
      (effects (font (size 1.27 1.27) (thickness 0.15)) (justify left bottom) hide)
    )
    (property "Footprint" "antmicro-footprints:R_0402_1005Metric" (at 323.215 66.675 0)
      (effects (font (size 1.27 1.27) (thickness 0.15)) (justify left bottom) hide)
    )
    (property "Datasheet" "https://industrial.panasonic.com/cdbs/www-data/pdf/RDA0000/AOA0000C301.pdf" (at 320.675 66.675 0)
      (effects (font (size 1.27 1.27) (thickness 0.15)) (justify left bottom) hide)
    )
    (property "Manufacturer" "Panasonic" (at 315.595 66.675 0)
      (effects (font (size 1.27 1.27) (thickness 0.15)) (justify left bottom) hide)
    )
    (property "MPN" "ERJ2GE0R00X" (at 318.135 66.675 0)
      (effects (font (size 1.27 1.27) (thickness 0.15)) (justify left bottom) hide)
    )
    (property "Val" "0R" (at 340.36 50.7999 90)
      (effects (font (size 1.27 1.27) (thickness 0.15)) (justify left))
    )
    (property "License" "Apache-2.0" (at 313.055 66.675 0)
      (effects (font (size 1.27 1.27) (thickness 0.15)) (justify left bottom) hide)
    )
    (property "Author" "Antmicro" (at 310.515 66.675 0)
      (effects (font (size 1.27 1.27) (thickness 0.15)) (justify left bottom) hide)
    )
    (property "Tolerance" "~" (at 328.295 66.675 0)
      (effects (font (size 1.27 1.27)) (justify left bottom) hide)
    )
    (property "Current" "1A" (at 307.975 66.675 0)
      (effects (font (size 1.27 1.27) (thickness 0.15)) (justify left bottom) hide)
    )
    (pin "1")
    (pin "2")
    (instances
      (project "data-center-rdimm-ddr4-tester"
        (path ""
          (reference "R145") (unit 1)
        )
      )
    )
  )

  (symbol (lib_id "antmicroResistors0402:R_0R_0402") (at 347.98 46.355 270) (unit 1)
    (in_bom yes) (on_board yes) (dnp no) (fields_autoplaced)
    (property "Reference" "R146" (at 350.52 47.625 90)
      (effects (font (size 1.524 1.524)) (justify left))
    )
    (property "Value" "R_0R_0402" (at 335.28 66.675 0)
      (effects (font (size 1.27 1.27) (thickness 0.15)) (justify left bottom) hide)
    )
    (property "Footprint" "antmicro-footprints:R_0402_1005Metric" (at 332.74 66.675 0)
      (effects (font (size 1.27 1.27) (thickness 0.15)) (justify left bottom) hide)
    )
    (property "Datasheet" "https://industrial.panasonic.com/cdbs/www-data/pdf/RDA0000/AOA0000C301.pdf" (at 330.2 66.675 0)
      (effects (font (size 1.27 1.27) (thickness 0.15)) (justify left bottom) hide)
    )
    (property "Manufacturer" "Panasonic" (at 325.12 66.675 0)
      (effects (font (size 1.27 1.27) (thickness 0.15)) (justify left bottom) hide)
    )
    (property "MPN" "ERJ2GE0R00X" (at 327.66 66.675 0)
      (effects (font (size 1.27 1.27) (thickness 0.15)) (justify left bottom) hide)
    )
    (property "Val" "0R" (at 350.52 50.7999 90)
      (effects (font (size 1.27 1.27) (thickness 0.15)) (justify left))
    )
    (property "License" "Apache-2.0" (at 322.58 66.675 0)
      (effects (font (size 1.27 1.27) (thickness 0.15)) (justify left bottom) hide)
    )
    (property "Author" "Antmicro" (at 320.04 66.675 0)
      (effects (font (size 1.27 1.27) (thickness 0.15)) (justify left bottom) hide)
    )
    (property "Tolerance" "~" (at 337.82 66.675 0)
      (effects (font (size 1.27 1.27)) (justify left bottom) hide)
    )
    (property "Current" "1A" (at 317.5 66.675 0)
      (effects (font (size 1.27 1.27) (thickness 0.15)) (justify left bottom) hide)
    )
    (pin "1")
    (pin "2")
    (instances
      (project "data-center-rdimm-ddr4-tester"
        (path ""
          (reference "R146") (unit 1)
        )
      )
    )
  )

  (symbol (lib_id "antmicropower:GND") (at 259.08 77.47 0) (unit 1)
    (in_bom yes) (on_board yes) (dnp no) (fields_autoplaced)
    (property "Reference" "#PWR0234" (at 259.08 83.82 0)
      (effects (font (size 1.27 1.27)) hide)
    )
    (property "Value" "GND" (at 259.08 81.915 0)
      (effects (font (size 1.27 1.27)))
    )
    (property "Footprint" "" (at 259.08 77.47 0)
      (effects (font (size 1.27 1.27)) hide)
    )
    (property "Datasheet" "" (at 259.08 77.47 0)
      (effects (font (size 1.27 1.27)) hide)
    )
    (property "Author" "Antmicro" (at 267.97 85.09 0)
      (effects (font (size 1.27 1.27) (thickness 0.15)) (justify left bottom) hide)
    )
    (property "License" "Apache-2.0" (at 267.97 87.63 0)
      (effects (font (size 1.27 1.27) (thickness 0.15)) (justify left bottom) hide)
    )
    (pin "1")
    (instances
      (project "data-center-rdimm-ddr4-tester"
        (path ""
          (reference "#PWR0234") (unit 1)
        )
      )
    )
  )

  (symbol (lib_id "antmicroResistors0402:R_20k_0402") (at 353.695 154.94 270) (unit 1)
    (in_bom yes) (on_board yes) (dnp no)
    (property "Reference" "R138" (at 353.695 154.305 90)
      (effects (font (size 1.524 1.524)) (justify left))
    )
    (property "Value" "R_20k_0402" (at 340.995 175.26 0)
      (effects (font (size 1.27 1.27) (thickness 0.15)) (justify left bottom) hide)
    )
    (property "Footprint" "antmicro-footprints:R_0402_1005Metric" (at 338.455 175.26 0)
      (effects (font (size 1.27 1.27) (thickness 0.15)) (justify left bottom) hide)
    )
    (property "Datasheet" "https://www.bourns.com/docs/product-datasheets/cr.pdf" (at 335.915 175.26 0)
      (effects (font (size 1.27 1.27) (thickness 0.15)) (justify left bottom) hide)
    )
    (property "Manufacturer" "Bourns" (at 330.835 175.26 0)
      (effects (font (size 1.27 1.27) (thickness 0.15)) (justify left bottom) hide)
    )
    (property "MPN" "CR0402-FX-2002GLF" (at 333.375 175.26 0)
      (effects (font (size 1.27 1.27) (thickness 0.15)) (justify left bottom) hide)
    )
    (property "Val" "20k" (at 353.695 160.655 90)
      (effects (font (size 1.27 1.27) (thickness 0.15)) (justify left))
    )
    (property "License" "Apache-2.0" (at 328.295 175.26 0)
      (effects (font (size 1.27 1.27) (thickness 0.15)) (justify left bottom) hide)
    )
    (property "Author" "Antmicro" (at 325.755 175.26 0)
      (effects (font (size 1.27 1.27) (thickness 0.15)) (justify left bottom) hide)
    )
    (property "Tolerance" "1%" (at 343.535 175.26 0)
      (effects (font (size 1.27 1.27)) (justify left bottom) hide)
    )
    (pin "1")
    (pin "2")
    (instances
      (project "data-center-rdimm-ddr4-tester"
        (path ""
          (reference "R138") (unit 1)
        )
      )
    )
  )

  (symbol (lib_id "antmicroResistors0402:R_20k_0402") (at 347.345 154.94 270) (unit 1)
    (in_bom yes) (on_board yes) (dnp no)
    (property "Reference" "R137" (at 347.345 154.305 90)
      (effects (font (size 1.524 1.524)) (justify left))
    )
    (property "Value" "R_20k_0402" (at 334.645 175.26 0)
      (effects (font (size 1.27 1.27) (thickness 0.15)) (justify left bottom) hide)
    )
    (property "Footprint" "antmicro-footprints:R_0402_1005Metric" (at 332.105 175.26 0)
      (effects (font (size 1.27 1.27) (thickness 0.15)) (justify left bottom) hide)
    )
    (property "Datasheet" "https://www.bourns.com/docs/product-datasheets/cr.pdf" (at 329.565 175.26 0)
      (effects (font (size 1.27 1.27) (thickness 0.15)) (justify left bottom) hide)
    )
    (property "Manufacturer" "Bourns" (at 324.485 175.26 0)
      (effects (font (size 1.27 1.27) (thickness 0.15)) (justify left bottom) hide)
    )
    (property "MPN" "CR0402-FX-2002GLF" (at 327.025 175.26 0)
      (effects (font (size 1.27 1.27) (thickness 0.15)) (justify left bottom) hide)
    )
    (property "Val" "20k" (at 347.345 160.655 90)
      (effects (font (size 1.27 1.27) (thickness 0.15)) (justify left))
    )
    (property "License" "Apache-2.0" (at 321.945 175.26 0)
      (effects (font (size 1.27 1.27) (thickness 0.15)) (justify left bottom) hide)
    )
    (property "Author" "Antmicro" (at 319.405 175.26 0)
      (effects (font (size 1.27 1.27) (thickness 0.15)) (justify left bottom) hide)
    )
    (property "Tolerance" "1%" (at 337.185 175.26 0)
      (effects (font (size 1.27 1.27)) (justify left bottom) hide)
    )
    (pin "1")
    (pin "2")
    (instances
      (project "data-center-rdimm-ddr4-tester"
        (path ""
          (reference "R137") (unit 1)
        )
      )
    )
  )

  (symbol (lib_id "antmicroResistors0402:R_20k_0402") (at 340.995 154.94 270) (unit 1)
    (in_bom yes) (on_board yes) (dnp no)
    (property "Reference" "R135" (at 340.995 154.305 90)
      (effects (font (size 1.524 1.524)) (justify left))
    )
    (property "Value" "R_20k_0402" (at 328.295 175.26 0)
      (effects (font (size 1.27 1.27) (thickness 0.15)) (justify left bottom) hide)
    )
    (property "Footprint" "antmicro-footprints:R_0402_1005Metric" (at 325.755 175.26 0)
      (effects (font (size 1.27 1.27) (thickness 0.15)) (justify left bottom) hide)
    )
    (property "Datasheet" "https://www.bourns.com/docs/product-datasheets/cr.pdf" (at 323.215 175.26 0)
      (effects (font (size 1.27 1.27) (thickness 0.15)) (justify left bottom) hide)
    )
    (property "Manufacturer" "Bourns" (at 318.135 175.26 0)
      (effects (font (size 1.27 1.27) (thickness 0.15)) (justify left bottom) hide)
    )
    (property "MPN" "CR0402-FX-2002GLF" (at 320.675 175.26 0)
      (effects (font (size 1.27 1.27) (thickness 0.15)) (justify left bottom) hide)
    )
    (property "Val" "20k" (at 340.995 160.655 90)
      (effects (font (size 1.27 1.27) (thickness 0.15)) (justify left))
    )
    (property "License" "Apache-2.0" (at 315.595 175.26 0)
      (effects (font (size 1.27 1.27) (thickness 0.15)) (justify left bottom) hide)
    )
    (property "Author" "Antmicro" (at 313.055 175.26 0)
      (effects (font (size 1.27 1.27) (thickness 0.15)) (justify left bottom) hide)
    )
    (property "Tolerance" "1%" (at 330.835 175.26 0)
      (effects (font (size 1.27 1.27)) (justify left bottom) hide)
    )
    (pin "1")
    (pin "2")
    (instances
      (project "data-center-rdimm-ddr4-tester"
        (path ""
          (reference "R135") (unit 1)
        )
      )
    )
  )

  (symbol (lib_id "antmicroResistors0402:R_20k_0402") (at 334.645 154.94 270) (unit 1)
    (in_bom yes) (on_board yes) (dnp no)
    (property "Reference" "R134" (at 334.645 154.305 90)
      (effects (font (size 1.524 1.524)) (justify left))
    )
    (property "Value" "R_20k_0402" (at 321.945 175.26 0)
      (effects (font (size 1.27 1.27) (thickness 0.15)) (justify left bottom) hide)
    )
    (property "Footprint" "antmicro-footprints:R_0402_1005Metric" (at 319.405 175.26 0)
      (effects (font (size 1.27 1.27) (thickness 0.15)) (justify left bottom) hide)
    )
    (property "Datasheet" "https://www.bourns.com/docs/product-datasheets/cr.pdf" (at 316.865 175.26 0)
      (effects (font (size 1.27 1.27) (thickness 0.15)) (justify left bottom) hide)
    )
    (property "Manufacturer" "Bourns" (at 311.785 175.26 0)
      (effects (font (size 1.27 1.27) (thickness 0.15)) (justify left bottom) hide)
    )
    (property "MPN" "CR0402-FX-2002GLF" (at 314.325 175.26 0)
      (effects (font (size 1.27 1.27) (thickness 0.15)) (justify left bottom) hide)
    )
    (property "Val" "20k" (at 334.645 160.655 90)
      (effects (font (size 1.27 1.27) (thickness 0.15)) (justify left))
    )
    (property "License" "Apache-2.0" (at 309.245 175.26 0)
      (effects (font (size 1.27 1.27) (thickness 0.15)) (justify left bottom) hide)
    )
    (property "Author" "Antmicro" (at 306.705 175.26 0)
      (effects (font (size 1.27 1.27) (thickness 0.15)) (justify left bottom) hide)
    )
    (property "Tolerance" "1%" (at 324.485 175.26 0)
      (effects (font (size 1.27 1.27)) (justify left bottom) hide)
    )
    (pin "1")
    (pin "2")
    (instances
      (project "data-center-rdimm-ddr4-tester"
        (path ""
          (reference "R134") (unit 1)
        )
      )
    )
  )

  (symbol (lib_id "antmicroResistors0402:R_20k_0402") (at 328.295 154.94 270) (unit 1)
    (in_bom yes) (on_board yes) (dnp no)
    (property "Reference" "R133" (at 328.295 154.305 90)
      (effects (font (size 1.524 1.524)) (justify left))
    )
    (property "Value" "R_20k_0402" (at 315.595 175.26 0)
      (effects (font (size 1.27 1.27) (thickness 0.15)) (justify left bottom) hide)
    )
    (property "Footprint" "antmicro-footprints:R_0402_1005Metric" (at 313.055 175.26 0)
      (effects (font (size 1.27 1.27) (thickness 0.15)) (justify left bottom) hide)
    )
    (property "Datasheet" "https://www.bourns.com/docs/product-datasheets/cr.pdf" (at 310.515 175.26 0)
      (effects (font (size 1.27 1.27) (thickness 0.15)) (justify left bottom) hide)
    )
    (property "Manufacturer" "Bourns" (at 305.435 175.26 0)
      (effects (font (size 1.27 1.27) (thickness 0.15)) (justify left bottom) hide)
    )
    (property "MPN" "CR0402-FX-2002GLF" (at 307.975 175.26 0)
      (effects (font (size 1.27 1.27) (thickness 0.15)) (justify left bottom) hide)
    )
    (property "Val" "20k" (at 328.295 160.655 90)
      (effects (font (size 1.27 1.27) (thickness 0.15)) (justify left))
    )
    (property "License" "Apache-2.0" (at 302.895 175.26 0)
      (effects (font (size 1.27 1.27) (thickness 0.15)) (justify left bottom) hide)
    )
    (property "Author" "Antmicro" (at 300.355 175.26 0)
      (effects (font (size 1.27 1.27) (thickness 0.15)) (justify left bottom) hide)
    )
    (property "Tolerance" "1%" (at 318.135 175.26 0)
      (effects (font (size 1.27 1.27)) (justify left bottom) hide)
    )
    (pin "1")
    (pin "2")
    (instances
      (project "data-center-rdimm-ddr4-tester"
        (path ""
          (reference "R133") (unit 1)
        )
      )
    )
  )

  (symbol (lib_id "antmicroResistors0402:R_20k_0402") (at 321.945 154.94 270) (unit 1)
    (in_bom yes) (on_board yes) (dnp no)
    (property "Reference" "R132" (at 321.945 154.305 90)
      (effects (font (size 1.524 1.524)) (justify left))
    )
    (property "Value" "R_20k_0402" (at 309.245 175.26 0)
      (effects (font (size 1.27 1.27) (thickness 0.15)) (justify left bottom) hide)
    )
    (property "Footprint" "antmicro-footprints:R_0402_1005Metric" (at 306.705 175.26 0)
      (effects (font (size 1.27 1.27) (thickness 0.15)) (justify left bottom) hide)
    )
    (property "Datasheet" "https://www.bourns.com/docs/product-datasheets/cr.pdf" (at 304.165 175.26 0)
      (effects (font (size 1.27 1.27) (thickness 0.15)) (justify left bottom) hide)
    )
    (property "Manufacturer" "Bourns" (at 299.085 175.26 0)
      (effects (font (size 1.27 1.27) (thickness 0.15)) (justify left bottom) hide)
    )
    (property "MPN" "CR0402-FX-2002GLF" (at 301.625 175.26 0)
      (effects (font (size 1.27 1.27) (thickness 0.15)) (justify left bottom) hide)
    )
    (property "Val" "20k" (at 321.945 160.655 90)
      (effects (font (size 1.27 1.27) (thickness 0.15)) (justify left))
    )
    (property "License" "Apache-2.0" (at 296.545 175.26 0)
      (effects (font (size 1.27 1.27) (thickness 0.15)) (justify left bottom) hide)
    )
    (property "Author" "Antmicro" (at 294.005 175.26 0)
      (effects (font (size 1.27 1.27) (thickness 0.15)) (justify left bottom) hide)
    )
    (property "Tolerance" "1%" (at 311.785 175.26 0)
      (effects (font (size 1.27 1.27)) (justify left bottom) hide)
    )
    (pin "1")
    (pin "2")
    (instances
      (project "data-center-rdimm-ddr4-tester"
        (path ""
          (reference "R132") (unit 1)
        )
      )
    )
  )

  (symbol (lib_id "antmicroResistors0402:R_20k_0402") (at 315.595 154.94 270) (unit 1)
    (in_bom yes) (on_board yes) (dnp no)
    (property "Reference" "R131" (at 315.595 154.305 90)
      (effects (font (size 1.524 1.524)) (justify left))
    )
    (property "Value" "R_20k_0402" (at 302.895 175.26 0)
      (effects (font (size 1.27 1.27) (thickness 0.15)) (justify left bottom) hide)
    )
    (property "Footprint" "antmicro-footprints:R_0402_1005Metric" (at 300.355 175.26 0)
      (effects (font (size 1.27 1.27) (thickness 0.15)) (justify left bottom) hide)
    )
    (property "Datasheet" "https://www.bourns.com/docs/product-datasheets/cr.pdf" (at 297.815 175.26 0)
      (effects (font (size 1.27 1.27) (thickness 0.15)) (justify left bottom) hide)
    )
    (property "Manufacturer" "Bourns" (at 292.735 175.26 0)
      (effects (font (size 1.27 1.27) (thickness 0.15)) (justify left bottom) hide)
    )
    (property "MPN" "CR0402-FX-2002GLF" (at 295.275 175.26 0)
      (effects (font (size 1.27 1.27) (thickness 0.15)) (justify left bottom) hide)
    )
    (property "Val" "20k" (at 315.595 160.655 90)
      (effects (font (size 1.27 1.27) (thickness 0.15)) (justify left))
    )
    (property "License" "Apache-2.0" (at 290.195 175.26 0)
      (effects (font (size 1.27 1.27) (thickness 0.15)) (justify left bottom) hide)
    )
    (property "Author" "Antmicro" (at 287.655 175.26 0)
      (effects (font (size 1.27 1.27) (thickness 0.15)) (justify left bottom) hide)
    )
    (property "Tolerance" "1%" (at 305.435 175.26 0)
      (effects (font (size 1.27 1.27)) (justify left bottom) hide)
    )
    (pin "1")
    (pin "2")
    (instances
      (project "data-center-rdimm-ddr4-tester"
        (path ""
          (reference "R131") (unit 1)
        )
      )
    )
  )

  (symbol (lib_id "antmicroResistors0402:R_220R_0402") (at 337.185 184.785 0) (unit 1)
    (in_bom yes) (on_board yes) (dnp no) (fields_autoplaced)
    (property "Reference" "R136" (at 339.725 188.595 0)
      (effects (font (size 1.524 1.524)))
    )
    (property "Value" "R_220R_0402" (at 357.505 197.485 0)
      (effects (font (size 1.27 1.27) (thickness 0.15)) (justify left bottom) hide)
    )
    (property "Footprint" "antmicro-footprints:R_0402_1005Metric" (at 357.505 200.025 0)
      (effects (font (size 1.27 1.27) (thickness 0.15)) (justify left bottom) hide)
    )
    (property "Datasheet" "https://www.bourns.com/docs/product-datasheets/cr.pdf" (at 357.505 202.565 0)
      (effects (font (size 1.27 1.27) (thickness 0.15)) (justify left bottom) hide)
    )
    (property "Manufacturer" "Bourns" (at 357.505 207.645 0)
      (effects (font (size 1.27 1.27) (thickness 0.15)) (justify left bottom) hide)
    )
    (property "MPN" "CR0402-FX-2200GLF" (at 357.505 205.105 0)
      (effects (font (size 1.27 1.27) (thickness 0.15)) (justify left bottom) hide)
    )
    (property "Val" "220R" (at 339.725 192.405 0)
      (effects (font (size 1.27 1.27) (thickness 0.15)))
    )
    (property "License" "Apache-2.0" (at 357.505 210.185 0)
      (effects (font (size 1.27 1.27) (thickness 0.15)) (justify left bottom) hide)
    )
    (property "Author" "Antmicro" (at 357.505 212.725 0)
      (effects (font (size 1.27 1.27) (thickness 0.15)) (justify left bottom) hide)
    )
    (property "Tolerance" "1%" (at 357.505 194.945 0)
      (effects (font (size 1.27 1.27)) (justify left bottom) hide)
    )
    (pin "1")
    (pin "2")
    (instances
      (project "data-center-rdimm-ddr4-tester"
        (path ""
          (reference "R136") (unit 1)
        )
      )
    )
  )

  (symbol (lib_id "antmicropower:GND") (at 317.5 205.74 0) (unit 1)
    (in_bom yes) (on_board yes) (dnp no) (fields_autoplaced)
    (property "Reference" "#PWR0235" (at 317.5 212.09 0)
      (effects (font (size 1.27 1.27)) hide)
    )
    (property "Value" "GND" (at 317.5 210.185 0)
      (effects (font (size 1.27 1.27)))
    )
    (property "Footprint" "" (at 317.5 205.74 0)
      (effects (font (size 1.27 1.27)) hide)
    )
    (property "Datasheet" "" (at 317.5 205.74 0)
      (effects (font (size 1.27 1.27)) hide)
    )
    (property "Author" "Antmicro" (at 326.39 213.36 0)
      (effects (font (size 1.27 1.27) (thickness 0.15)) (justify left bottom) hide)
    )
    (property "License" "Apache-2.0" (at 326.39 215.9 0)
      (effects (font (size 1.27 1.27) (thickness 0.15)) (justify left bottom) hide)
    )
    (pin "1")
    (instances
      (project "data-center-rdimm-ddr4-tester"
        (path ""
          (reference "#PWR0235") (unit 1)
        )
      )
    )
  )

  (symbol (lib_id "antmicropower:GND") (at 404.495 193.04 0) (mirror y) (unit 1)
    (in_bom yes) (on_board yes) (dnp no) (fields_autoplaced)
    (property "Reference" "#PWR0236" (at 404.495 199.39 0)
      (effects (font (size 1.27 1.27)) hide)
    )
    (property "Value" "GND" (at 404.495 197.485 0)
      (effects (font (size 1.27 1.27)))
    )
    (property "Footprint" "" (at 404.495 193.04 0)
      (effects (font (size 1.27 1.27)) hide)
    )
    (property "Datasheet" "" (at 404.495 193.04 0)
      (effects (font (size 1.27 1.27)) hide)
    )
    (property "Author" "Antmicro" (at 395.605 200.66 0)
      (effects (font (size 1.27 1.27) (thickness 0.15)) (justify left bottom) hide)
    )
    (property "License" "Apache-2.0" (at 395.605 203.2 0)
      (effects (font (size 1.27 1.27) (thickness 0.15)) (justify left bottom) hide)
    )
    (pin "1")
    (instances
      (project "data-center-rdimm-ddr4-tester"
        (path ""
          (reference "#PWR0236") (unit 1)
        )
      )
    )
  )

  (symbol (lib_id "antmicroTransistorsFETsMOSFETsSingle:BSS138PW") (at 54.61 223.52 90) (unit 1)
    (in_bom yes) (on_board yes) (dnp no)
    (property "Reference" "Q2" (at 52.07 208.915 90)
      (effects (font (size 1.524 1.524)))
    )
    (property "Value" "BSS138PW" (at 52.07 211.455 90)
      (effects (font (size 1.27 1.27) (thickness 0.15)))
    )
    (property "Footprint" "antmicro-footprints:SC70-3" (at 66.04 200.66 0)
      (effects (font (size 1.27 1.27) (thickness 0.15)) (justify left bottom) hide)
    )
    (property "Datasheet" "https://assets.nexperia.com/documents/data-sheet/BSS138PW.pdf" (at 68.58 200.66 0)
      (effects (font (size 1.27 1.27) (thickness 0.15)) (justify left bottom) hide)
    )
    (property "MPN" "BSS138PW" (at 71.12 200.66 0)
      (effects (font (size 1.27 1.27) (thickness 0.15)) (justify left bottom) hide)
    )
    (property "Manufacturer" "Nexperia" (at 73.66 200.66 0)
      (effects (font (size 1.27 1.27) (thickness 0.15)) (justify left bottom) hide)
    )
    (property "Author" "Antmicro" (at 76.2 200.66 0)
      (effects (font (size 1.27 1.27) (thickness 0.15)) (justify left bottom) hide)
    )
    (property "License" "Apache-2.0" (at 78.74 200.66 0)
      (effects (font (size 1.27 1.27) (thickness 0.15)) (justify left bottom) hide)
    )
    (pin "1")
    (pin "2")
    (pin "3")
    (instances
      (project "data-center-rdimm-ddr4-tester"
        (path ""
          (reference "Q2") (unit 1)
        )
      )
    )
  )

  (symbol (lib_id "antmicroTransistorsFETsMOSFETsSingle:BSS138PW") (at 55.245 243.205 90) (unit 1)
    (in_bom yes) (on_board yes) (dnp no)
    (property "Reference" "Q4" (at 52.705 228.6 90)
      (effects (font (size 1.524 1.524)))
    )
    (property "Value" "BSS138PW" (at 52.705 231.14 90)
      (effects (font (size 1.27 1.27) (thickness 0.15)))
    )
    (property "Footprint" "antmicro-footprints:SC70-3" (at 66.675 220.345 0)
      (effects (font (size 1.27 1.27) (thickness 0.15)) (justify left bottom) hide)
    )
    (property "Datasheet" "https://assets.nexperia.com/documents/data-sheet/BSS138PW.pdf" (at 69.215 220.345 0)
      (effects (font (size 1.27 1.27) (thickness 0.15)) (justify left bottom) hide)
    )
    (property "MPN" "BSS138PW" (at 71.755 220.345 0)
      (effects (font (size 1.27 1.27) (thickness 0.15)) (justify left bottom) hide)
    )
    (property "Manufacturer" "Nexperia" (at 74.295 220.345 0)
      (effects (font (size 1.27 1.27) (thickness 0.15)) (justify left bottom) hide)
    )
    (property "Author" "Antmicro" (at 76.835 220.345 0)
      (effects (font (size 1.27 1.27) (thickness 0.15)) (justify left bottom) hide)
    )
    (property "License" "Apache-2.0" (at 79.375 220.345 0)
      (effects (font (size 1.27 1.27) (thickness 0.15)) (justify left bottom) hide)
    )
    (pin "1")
    (pin "2")
    (pin "3")
    (instances
      (project "data-center-rdimm-ddr4-tester"
        (path ""
          (reference "Q4") (unit 1)
        )
      )
    )
  )

  (symbol (lib_id "antmicroTransistorsFETsMOSFETsSingle:BSS138PW") (at 109.855 223.52 90) (unit 1)
    (in_bom yes) (on_board yes) (dnp no)
    (property "Reference" "Q5" (at 107.315 208.915 90)
      (effects (font (size 1.524 1.524)))
    )
    (property "Value" "BSS138PW" (at 107.315 211.455 90)
      (effects (font (size 1.27 1.27) (thickness 0.15)))
    )
    (property "Footprint" "antmicro-footprints:SC70-3" (at 121.285 200.66 0)
      (effects (font (size 1.27 1.27) (thickness 0.15)) (justify left bottom) hide)
    )
    (property "Datasheet" "https://assets.nexperia.com/documents/data-sheet/BSS138PW.pdf" (at 123.825 200.66 0)
      (effects (font (size 1.27 1.27) (thickness 0.15)) (justify left bottom) hide)
    )
    (property "MPN" "BSS138PW" (at 126.365 200.66 0)
      (effects (font (size 1.27 1.27) (thickness 0.15)) (justify left bottom) hide)
    )
    (property "Manufacturer" "Nexperia" (at 128.905 200.66 0)
      (effects (font (size 1.27 1.27) (thickness 0.15)) (justify left bottom) hide)
    )
    (property "Author" "Antmicro" (at 131.445 200.66 0)
      (effects (font (size 1.27 1.27) (thickness 0.15)) (justify left bottom) hide)
    )
    (property "License" "Apache-2.0" (at 133.985 200.66 0)
      (effects (font (size 1.27 1.27) (thickness 0.15)) (justify left bottom) hide)
    )
    (pin "1")
    (pin "2")
    (pin "3")
    (instances
      (project "data-center-rdimm-ddr4-tester"
        (path ""
          (reference "Q5") (unit 1)
        )
      )
    )
  )

  (symbol (lib_id "antmicroTransistorsFETsMOSFETsSingle:BSS138PW") (at 109.855 243.205 90) (unit 1)
    (in_bom yes) (on_board yes) (dnp no)
    (property "Reference" "Q6" (at 107.315 228.6 90)
      (effects (font (size 1.524 1.524)))
    )
    (property "Value" "BSS138PW" (at 107.315 231.14 90)
      (effects (font (size 1.27 1.27) (thickness 0.15)))
    )
    (property "Footprint" "antmicro-footprints:SC70-3" (at 121.285 220.345 0)
      (effects (font (size 1.27 1.27) (thickness 0.15)) (justify left bottom) hide)
    )
    (property "Datasheet" "https://assets.nexperia.com/documents/data-sheet/BSS138PW.pdf" (at 123.825 220.345 0)
      (effects (font (size 1.27 1.27) (thickness 0.15)) (justify left bottom) hide)
    )
    (property "MPN" "BSS138PW" (at 126.365 220.345 0)
      (effects (font (size 1.27 1.27) (thickness 0.15)) (justify left bottom) hide)
    )
    (property "Manufacturer" "Nexperia" (at 128.905 220.345 0)
      (effects (font (size 1.27 1.27) (thickness 0.15)) (justify left bottom) hide)
    )
    (property "Author" "Antmicro" (at 131.445 220.345 0)
      (effects (font (size 1.27 1.27) (thickness 0.15)) (justify left bottom) hide)
    )
    (property "License" "Apache-2.0" (at 133.985 220.345 0)
      (effects (font (size 1.27 1.27) (thickness 0.15)) (justify left bottom) hide)
    )
    (pin "1")
    (pin "2")
    (pin "3")
    (instances
      (project "data-center-rdimm-ddr4-tester"
        (path ""
          (reference "Q6") (unit 1)
        )
      )
    )
  )

  (symbol (lib_id "antmicroTransistorsFETsMOSFETsSingle:BSS138PW") (at 54.61 262.89 90) (unit 1)
    (in_bom yes) (on_board yes) (dnp no)
    (property "Reference" "Q3" (at 52.07 248.285 90)
      (effects (font (size 1.524 1.524)))
    )
    (property "Value" "BSS138PW" (at 52.07 250.825 90)
      (effects (font (size 1.27 1.27) (thickness 0.15)))
    )
    (property "Footprint" "antmicro-footprints:SC70-3" (at 66.04 240.03 0)
      (effects (font (size 1.27 1.27) (thickness 0.15)) (justify left bottom) hide)
    )
    (property "Datasheet" "https://assets.nexperia.com/documents/data-sheet/BSS138PW.pdf" (at 68.58 240.03 0)
      (effects (font (size 1.27 1.27) (thickness 0.15)) (justify left bottom) hide)
    )
    (property "MPN" "BSS138PW" (at 71.12 240.03 0)
      (effects (font (size 1.27 1.27) (thickness 0.15)) (justify left bottom) hide)
    )
    (property "Manufacturer" "Nexperia" (at 73.66 240.03 0)
      (effects (font (size 1.27 1.27) (thickness 0.15)) (justify left bottom) hide)
    )
    (property "Author" "Antmicro" (at 76.2 240.03 0)
      (effects (font (size 1.27 1.27) (thickness 0.15)) (justify left bottom) hide)
    )
    (property "License" "Apache-2.0" (at 78.74 240.03 0)
      (effects (font (size 1.27 1.27) (thickness 0.15)) (justify left bottom) hide)
    )
    (pin "1")
    (pin "2")
    (pin "3")
    (instances
      (project "data-center-rdimm-ddr4-tester"
        (path ""
          (reference "Q3") (unit 1)
        )
      )
    )
  )

  (symbol (lib_id "data-center-rdimm-ddr4-tester:Oscillator_SMD_12MHz_KX-7") (at 53.975 114.3 0) (unit 1)
    (in_bom yes) (on_board yes) (dnp no)
    (property "Reference" "Y2" (at 57.785 106.68 0)
      (effects (font (size 1.27 1.27)))
    )
    (property "Value" "Oscillator_SMD_12MHz_KX-7" (at 57.785 109.22 0)
      (effects (font (size 1.27 1.27) (thickness 0.15)) hide)
    )
    (property "Footprint" "data-center-rdimm-ddr4-tester-footprints:Oscillator_SMD_Geyer_KX-7-4Pin_3.2x2.5mm" (at 79.375 124.46 0)
      (effects (font (size 1.27 1.27) (thickness 0.15)) (justify left bottom) hide)
    )
    (property "Datasheet" "" (at 79.375 127 0)
      (effects (font (size 1.27 1.27) (thickness 0.15)) (justify left bottom) hide)
    )
    (property "MPN" "ABM8G-12.000MHZ-18-D2Y-T " (at 62.865 109.22 0)
      (effects (font (size 1.27 1.27) (thickness 0.15)))
    )
    (property "Manufacturer" "Abracon" (at 79.375 132.08 0)
      (effects (font (size 1.27 1.27) (thickness 0.15)) (justify left bottom) hide)
    )
    (property "Val" "12MHz" (at 79.375 134.62 0)
      (effects (font (size 1.27 1.27) (thickness 0.15)) (justify left bottom) hide)
    )
    (property "Author" "Antmicro" (at 79.375 137.16 0)
      (effects (font (size 1.27 1.27) (thickness 0.15)) (justify left bottom) hide)
    )
    (property "License" "Apache-2.0" (at 79.375 139.7 0)
      (effects (font (size 1.27 1.27) (thickness 0.15)) (justify left bottom) hide)
    )
    (pin "1")
    (pin "2")
    (pin "3")
    (pin "4")
    (instances
      (project "data-center-rdimm-ddr4-tester"
        (path ""
          (reference "Y2") (unit 1)
        )
      )
    )
  )

  (symbol (lib_id "antmicropower:GND") (at 57.785 120.65 0) (unit 1)
    (in_bom yes) (on_board yes) (dnp no) (fields_autoplaced)
    (property "Reference" "#PWR0137" (at 57.785 127 0)
      (effects (font (size 1.27 1.27)) hide)
    )
    (property "Value" "GND" (at 57.785 125.73 0)
      (effects (font (size 1.27 1.27)))
    )
    (property "Footprint" "" (at 57.785 120.65 0)
      (effects (font (size 1.27 1.27)) hide)
    )
    (property "Datasheet" "" (at 57.785 120.65 0)
      (effects (font (size 1.27 1.27)) hide)
    )
    (property "Author" "Antmicro" (at 66.675 128.27 0)
      (effects (font (size 1.27 1.27) (thickness 0.15)) (justify left bottom) hide)
    )
    (property "License" "Apache-2.0" (at 66.675 130.81 0)
      (effects (font (size 1.27 1.27) (thickness 0.15)) (justify left bottom) hide)
    )
    (pin "1")
    (instances
      (project "data-center-rdimm-ddr4-tester"
        (path ""
          (reference "#PWR0137") (unit 1)
        )
      )
    )
  )

  (symbol (lib_id "antmicroTestPoints:TP_1mm_SMD") (at 130.175 63.5 0) (unit 1)
    (in_bom yes) (on_board yes) (dnp no)
    (property "Reference" "TP11" (at 137.16 63.5 0)
      (effects (font (size 1.27 1.27)))
    )
    (property "Value" "TP_1mm_SMD" (at 145.415 71.12 0)
      (effects (font (size 1.27 1.27) (thickness 0.15)) (justify left bottom) hide)
    )
    (property "Footprint" "antmicro-footprints:TP_SMD_1mm" (at 145.415 73.66 0)
      (effects (font (size 1.27 1.27) (thickness 0.15)) (justify left bottom) hide)
    )
    (property "Datasheet" "" (at 145.415 76.2 0)
      (effects (font (size 1.27 1.27) (thickness 0.15)) (justify left bottom) hide)
    )
    (property "MPN" "" (at 130.175 63.5 0)
      (effects (font (size 1.27 1.27)) hide)
    )
    (property "Manufacturer" "" (at 130.175 63.5 0)
      (effects (font (size 1.27 1.27)) hide)
    )
    (property "Author" "Antmicro" (at 145.415 78.74 0)
      (effects (font (size 1.27 1.27) (thickness 0.15)) (justify left bottom) hide)
    )
    (property "License" "Apache-2.0" (at 145.415 81.28 0)
      (effects (font (size 1.27 1.27) (thickness 0.15)) (justify left bottom) hide)
    )
    (pin "1")
    (instances
      (project "data-center-rdimm-ddr4-tester"
        (path ""
          (reference "TP11") (unit 1)
        )
      )
    )
  )

  (symbol (lib_id "antmicroMemoryConnectorsPCCardSockets:MicroSD_693071020811") (at 361.95 164.465 0) (unit 1)
    (in_bom yes) (on_board yes) (dnp no) (fields_autoplaced)
    (property "Reference" "J7" (at 384.175 154.94 0)
      (effects (font (size 1.27 1.27)))
    )
    (property "Value" "MicroSD_693071020811" (at 384.175 158.115 0)
      (effects (font (size 1.27 1.27) (thickness 0.15)) hide)
    )
    (property "Footprint" "antmicro-footprints:MicroSD_Wurth_693071020811" (at 417.83 172.085 0)
      (effects (font (size 1.27 1.27) (thickness 0.15)) (justify left bottom) hide)
    )
    (property "Datasheet" "https://www.we-online.com/catalog/datasheet/693071020811.pdf" (at 417.83 174.625 0)
      (effects (font (size 1.27 1.27) (thickness 0.15)) (justify left bottom) hide)
    )
    (property "MPN" "693071020811" (at 384.175 157.48 0)
      (effects (font (size 1.27 1.27) (thickness 0.15)))
    )
    (property "Manufacturer" "Würth Elektronik" (at 417.83 177.165 0)
      (effects (font (size 1.27 1.27) (thickness 0.15)) (justify left bottom) hide)
    )
    (property "Author" "Antmicro" (at 417.83 182.245 0)
      (effects (font (size 1.27 1.27) (thickness 0.15)) (justify left bottom) hide)
    )
    (property "License" "Apache-2.0" (at 417.83 184.785 0)
      (effects (font (size 1.27 1.27) (thickness 0.15)) (justify left bottom) hide)
    )
    (pin "1")
    (pin "2")
    (pin "3")
    (pin "4")
    (pin "5")
    (pin "6")
    (pin "7")
    (pin "8")
    (pin "9")
    (pin "SH")
    (instances
      (project "data-center-rdimm-ddr4-tester"
        (path ""
          (reference "J7") (unit 1)
        )
      )
    )
  )

  (symbol (lib_id "antmicroCapacitors0402:C_100n_0402") (at 384.175 67.31 180) (unit 1)
    (in_bom yes) (on_board yes) (dnp no)
    (property "Reference" "C252" (at 381.6414 61.595 0)
      (effects (font (size 1.524 1.524)))
    )
    (property "Value" "C_100n_0402" (at 363.855 57.15 0)
      (effects (font (size 1.27 1.27) (thickness 0.15)) (justify left bottom) hide)
    )
    (property "Footprint" "antmicro-footprints:C_0402_1005Metric" (at 363.855 54.61 0)
      (effects (font (size 1.27 1.27) (thickness 0.15)) (justify left bottom) hide)
    )
    (property "Datasheet" "https://search.murata.co.jp/Ceramy/image/img/A01X/G101/ENG/GRM155R61H104KE14-01.pdf" (at 363.855 52.07 0)
      (effects (font (size 1.27 1.27) (thickness 0.15)) (justify left bottom) hide)
    )
    (property "Manufacturer" "Murata" (at 363.855 46.99 0)
      (effects (font (size 1.27 1.27) (thickness 0.15)) (justify left bottom) hide)
    )
    (property "MPN" "GRM155R61H104KE14D" (at 363.855 49.53 0)
      (effects (font (size 1.27 1.27) (thickness 0.15)) (justify left bottom) hide)
    )
    (property "Val" "100n" (at 381.635 64.135 0)
      (effects (font (size 1.27 1.27) (thickness 0.15)))
    )
    (property "License" "Apache-2.0" (at 363.855 44.45 0)
      (effects (font (size 1.27 1.27) (thickness 0.15)) (justify left bottom) hide)
    )
    (property "Author" "Antmicro" (at 363.855 41.91 0)
      (effects (font (size 1.27 1.27) (thickness 0.15)) (justify left bottom) hide)
    )
    (property "Voltage" "50V" (at 363.855 39.37 0)
      (effects (font (size 1.27 1.27)) (justify left bottom) hide)
    )
    (property "Dielectric" "X5R" (at 363.855 36.83 0)
      (effects (font (size 1.27 1.27)) (justify left bottom) hide)
    )
    (pin "1")
    (pin "2")
    (instances
      (project "data-center-rdimm-ddr4-tester"
        (path ""
          (reference "C252") (unit 1)
        )
      )
    )
  )

  (symbol (lib_id "antmicropower:GND") (at 361.315 193.04 0) (unit 1)
    (in_bom yes) (on_board yes) (dnp no) (fields_autoplaced)
    (property "Reference" "#PWR0344" (at 361.315 199.39 0)
      (effects (font (size 1.27 1.27)) hide)
    )
    (property "Value" "GND" (at 361.315 197.485 0)
      (effects (font (size 1.27 1.27)))
    )
    (property "Footprint" "" (at 361.315 193.04 0)
      (effects (font (size 1.27 1.27)) hide)
    )
    (property "Datasheet" "" (at 361.315 193.04 0)
      (effects (font (size 1.27 1.27)) hide)
    )
    (property "Author" "Antmicro" (at 370.205 200.66 0)
      (effects (font (size 1.27 1.27) (thickness 0.15)) (justify left bottom) hide)
    )
    (property "License" "Apache-2.0" (at 370.205 203.2 0)
      (effects (font (size 1.27 1.27) (thickness 0.15)) (justify left bottom) hide)
    )
    (pin "1")
    (instances
      (project "data-center-rdimm-ddr4-tester"
        (path ""
          (reference "#PWR0344") (unit 1)
        )
      )
    )
  )

  (symbol (lib_id "antmicroResistors0402:R_5k11_0402") (at 227.33 157.48 0) (unit 1)
    (in_bom yes) (on_board yes) (dnp no)
    (property "Reference" "R15" (at 225.425 156.21 0)
      (effects (font (size 1.524 1.524)))
    )
    (property "Value" "R_5k11_0402" (at 247.65 170.18 0)
      (effects (font (size 1.27 1.27) (thickness 0.15)) (justify left bottom) hide)
    )
    (property "Footprint" "antmicro-footprints:R_0402_1005Metric" (at 247.65 172.72 0)
      (effects (font (size 1.27 1.27) (thickness 0.15)) (justify left bottom) hide)
    )
    (property "Datasheet" "https://www.bourns.com/docs/product-datasheets/cr.pdf" (at 247.65 175.26 0)
      (effects (font (size 1.27 1.27) (thickness 0.15)) (justify left bottom) hide)
    )
    (property "Manufacturer" "Bourns" (at 247.65 180.34 0)
      (effects (font (size 1.27 1.27) (thickness 0.15)) (justify left bottom) hide)
    )
    (property "MPN" "CR0402-FX-5111GLF" (at 247.65 177.8 0)
      (effects (font (size 1.27 1.27) (thickness 0.15)) (justify left bottom) hide)
    )
    (property "Val" "5k11" (at 234.315 156.21 0)
      (effects (font (size 1.27 1.27) (thickness 0.15)))
    )
    (property "License" "Apache-2.0" (at 247.65 182.88 0)
      (effects (font (size 1.27 1.27) (thickness 0.15)) (justify left bottom) hide)
    )
    (property "Author" "Antmicro" (at 247.65 185.42 0)
      (effects (font (size 1.27 1.27) (thickness 0.15)) (justify left bottom) hide)
    )
    (property "Tolerance" "1%" (at 247.65 167.64 0)
      (effects (font (size 1.27 1.27)) (justify left bottom) hide)
    )
    (pin "1")
    (pin "2")
    (instances
      (project "data-center-rdimm-ddr4-tester"
        (path ""
          (reference "R15") (unit 1)
        )
      )
    )
  )

  (symbol (lib_id "antmicroTransistorsFETsMOSFETsSingle:BSS138PW") (at 189.23 263.525 0) (unit 1)
    (in_bom yes) (on_board yes) (dnp no) (fields_autoplaced)
    (property "Reference" "Q9" (at 200.66 259.715 0)
      (effects (font (size 1.524 1.524)) (justify left))
    )
    (property "Value" "BSS138PW" (at 200.66 262.8899 0)
      (effects (font (size 1.27 1.27) (thickness 0.15)) (justify left))
    )
    (property "Footprint" "antmicro-footprints:SC70-3" (at 212.09 274.955 0)
      (effects (font (size 1.27 1.27) (thickness 0.15)) (justify left bottom) hide)
    )
    (property "Datasheet" "https://assets.nexperia.com/documents/data-sheet/BSS138PW.pdf" (at 212.09 277.495 0)
      (effects (font (size 1.27 1.27) (thickness 0.15)) (justify left bottom) hide)
    )
    (property "MPN" "BSS138PW" (at 212.09 280.035 0)
      (effects (font (size 1.27 1.27) (thickness 0.15)) (justify left bottom) hide)
    )
    (property "Manufacturer" "Nexperia" (at 212.09 282.575 0)
      (effects (font (size 1.27 1.27) (thickness 0.15)) (justify left bottom) hide)
    )
    (property "Author" "Antmicro" (at 212.09 285.115 0)
      (effects (font (size 1.27 1.27) (thickness 0.15)) (justify left bottom) hide)
    )
    (property "License" "Apache-2.0" (at 212.09 287.655 0)
      (effects (font (size 1.27 1.27) (thickness 0.15)) (justify left bottom) hide)
    )
    (pin "1")
    (pin "2")
    (pin "3")
    (instances
      (project "data-center-rdimm-ddr4-tester"
        (path ""
          (reference "Q9") (unit 1)
        )
      )
    )
  )

  (symbol (lib_id "antmicroResistors0402:R_4k7_0402") (at 259.08 237.49 270) (unit 1)
    (in_bom yes) (on_board yes) (dnp no) (fields_autoplaced)
    (property "Reference" "R190" (at 257.175 238.76 90)
      (effects (font (size 1.524 1.524)) (justify right))
    )
    (property "Value" "R_4k7_0402" (at 246.38 257.81 0)
      (effects (font (size 1.27 1.27) (thickness 0.15)) (justify left bottom) hide)
    )
    (property "Footprint" "antmicro-footprints:R_0402_1005Metric" (at 243.84 257.81 0)
      (effects (font (size 1.27 1.27) (thickness 0.15)) (justify left bottom) hide)
    )
    (property "Datasheet" "https://www.bourns.com/docs/product-datasheets/cr.pdf" (at 241.3 257.81 0)
      (effects (font (size 1.27 1.27) (thickness 0.15)) (justify left bottom) hide)
    )
    (property "Manufacturer" "Bourns" (at 236.22 257.81 0)
      (effects (font (size 1.27 1.27) (thickness 0.15)) (justify left bottom) hide)
    )
    (property "MPN" "CR0402-FX-4701GLF" (at 238.76 257.81 0)
      (effects (font (size 1.27 1.27) (thickness 0.15)) (justify left bottom) hide)
    )
    (property "Val" "4k7" (at 257.175 241.9349 90)
      (effects (font (size 1.27 1.27) (thickness 0.15)) (justify right))
    )
    (property "License" "Apache-2.0" (at 233.68 257.81 0)
      (effects (font (size 1.27 1.27) (thickness 0.15)) (justify left bottom) hide)
    )
    (property "Author" "Antmicro" (at 231.14 257.81 0)
      (effects (font (size 1.27 1.27) (thickness 0.15)) (justify left bottom) hide)
    )
    (property "Tolerance" "1%" (at 248.92 257.81 0)
      (effects (font (size 1.27 1.27)) (justify left bottom) hide)
    )
    (pin "1")
    (pin "2")
    (instances
      (project "data-center-rdimm-ddr4-tester"
        (path ""
          (reference "R190") (unit 1)
        )
      )
    )
  )

  (symbol (lib_id "antmicroCapacitors0402:C_1u_0402") (at 317.5 200.66 270) (unit 1)
    (in_bom yes) (on_board yes) (dnp no) (fields_autoplaced)
    (property "Reference" "C10" (at 320.04 201.9363 90)
      (effects (font (size 1.524 1.524)) (justify left))
    )
    (property "Value" "C_1u_0402" (at 307.34 220.98 0)
      (effects (font (size 1.27 1.27) (thickness 0.15)) (justify left bottom) hide)
    )
    (property "Footprint" "antmicro-footprints:C_0402_1005Metric" (at 304.8 220.98 0)
      (effects (font (size 1.27 1.27) (thickness 0.15)) (justify left bottom) hide)
    )
    (property "Datasheet" " " (at 302.26 220.98 0)
      (effects (font (size 1.27 1.27) (thickness 0.15)) (justify left bottom) hide)
    )
    (property "Manufacturer" "TDK" (at 297.18 220.98 0)
      (effects (font (size 1.27 1.27) (thickness 0.15)) (justify left bottom) hide)
    )
    (property "MPN" "C1005X6S1A105K050BC" (at 299.72 220.98 0)
      (effects (font (size 1.27 1.27) (thickness 0.15)) (justify left bottom) hide)
    )
    (property "Val" "1u" (at 320.04 205.1112 90)
      (effects (font (size 1.27 1.27) (thickness 0.15)) (justify left))
    )
    (property "License" "Apache-2.0" (at 294.64 220.98 0)
      (effects (font (size 1.27 1.27) (thickness 0.15)) (justify left bottom) hide)
    )
    (property "Author" "Antmicro" (at 292.1 220.98 0)
      (effects (font (size 1.27 1.27) (thickness 0.15)) (justify left bottom) hide)
    )
    (property "Voltage" "" (at 289.56 220.98 0)
      (effects (font (size 1.27 1.27)) (justify left bottom) hide)
    )
    (property "Dielectric" "" (at 287.02 220.98 0)
      (effects (font (size 1.27 1.27)) (justify left bottom) hide)
    )
    (pin "1")
    (pin "2")
    (instances
      (project "data-center-rdimm-ddr4-tester"
        (path ""
          (reference "C10") (unit 1)
        )
      )
    )
  )

  (symbol (lib_id "antmicroResistors0402:R_5k11_0402") (at 232.41 160.02 180) (unit 1)
    (in_bom yes) (on_board yes) (dnp no)
    (property "Reference" "R16" (at 225.425 158.75 0)
      (effects (font (size 1.524 1.524)))
    )
    (property "Value" "R_5k11_0402" (at 212.09 147.32 0)
      (effects (font (size 1.27 1.27) (thickness 0.15)) (justify left bottom) hide)
    )
    (property "Footprint" "antmicro-footprints:R_0402_1005Metric" (at 212.09 144.78 0)
      (effects (font (size 1.27 1.27) (thickness 0.15)) (justify left bottom) hide)
    )
    (property "Datasheet" "https://www.bourns.com/docs/product-datasheets/cr.pdf" (at 212.09 142.24 0)
      (effects (font (size 1.27 1.27) (thickness 0.15)) (justify left bottom) hide)
    )
    (property "Manufacturer" "Bourns" (at 212.09 137.16 0)
      (effects (font (size 1.27 1.27) (thickness 0.15)) (justify left bottom) hide)
    )
    (property "MPN" "CR0402-FX-5111GLF" (at 212.09 139.7 0)
      (effects (font (size 1.27 1.27) (thickness 0.15)) (justify left bottom) hide)
    )
    (property "Val" "5k11" (at 234.315 158.75 0)
      (effects (font (size 1.27 1.27) (thickness 0.15)))
    )
    (property "License" "Apache-2.0" (at 212.09 134.62 0)
      (effects (font (size 1.27 1.27) (thickness 0.15)) (justify left bottom) hide)
    )
    (property "Author" "Antmicro" (at 212.09 132.08 0)
      (effects (font (size 1.27 1.27) (thickness 0.15)) (justify left bottom) hide)
    )
    (property "Tolerance" "1%" (at 212.09 149.86 0)
      (effects (font (size 1.27 1.27)) (justify left bottom) hide)
    )
    (pin "1")
    (pin "2")
    (instances
      (project "data-center-rdimm-ddr4-tester"
        (path ""
          (reference "R16") (unit 1)
        )
      )
    )
  )

  (symbol (lib_id "antmicroResistors0402:R_330R_0402") (at 177.8 238.125 270) (unit 1)
    (in_bom yes) (on_board yes) (dnp no) (fields_autoplaced)
    (property "Reference" "R187" (at 180.34 239.395 90)
      (effects (font (size 1.524 1.524)) (justify left))
    )
    (property "Value" "R_330R_0402" (at 165.1 258.445 0)
      (effects (font (size 1.27 1.27) (thickness 0.15)) (justify left bottom) hide)
    )
    (property "Footprint" "antmicro-footprints:R_0402_1005Metric" (at 162.56 258.445 0)
      (effects (font (size 1.27 1.27) (thickness 0.15)) (justify left bottom) hide)
    )
    (property "Datasheet" "https://www.bourns.com/docs/product-datasheets/cr.pdf" (at 160.02 258.445 0)
      (effects (font (size 1.27 1.27) (thickness 0.15)) (justify left bottom) hide)
    )
    (property "Manufacturer" "Bourns" (at 154.94 258.445 0)
      (effects (font (size 1.27 1.27) (thickness 0.15)) (justify left bottom) hide)
    )
    (property "MPN" "CR0402-FX-3300GLF" (at 157.48 258.445 0)
      (effects (font (size 1.27 1.27) (thickness 0.15)) (justify left bottom) hide)
    )
    (property "Val" "330R" (at 180.34 242.5699 90)
      (effects (font (size 1.27 1.27) (thickness 0.15)) (justify left))
    )
    (property "License" "Apache-2.0" (at 152.4 258.445 0)
      (effects (font (size 1.27 1.27) (thickness 0.15)) (justify left bottom) hide)
    )
    (property "Author" "Antmicro" (at 149.86 258.445 0)
      (effects (font (size 1.27 1.27) (thickness 0.15)) (justify left bottom) hide)
    )
    (property "Tolerance" "1%" (at 167.64 258.445 0)
      (effects (font (size 1.27 1.27)) (justify left bottom) hide)
    )
    (pin "1")
    (pin "2")
    (instances
      (project "data-center-rdimm-ddr4-tester"
        (path ""
          (reference "R187") (unit 1)
        )
      )
    )
  )

  (symbol (lib_id "antmicropower:GND1") (at 238.76 92.71 0) (unit 1)
    (in_bom yes) (on_board yes) (dnp no) (fields_autoplaced)
    (property "Reference" "#PWR0395" (at 238.76 99.06 0)
      (effects (font (size 1.27 1.27)) hide)
    )
    (property "Value" "GND1" (at 238.76 97.155 0)
      (effects (font (size 1.27 1.27)))
    )
    (property "Footprint" "" (at 238.76 92.71 0)
      (effects (font (size 1.27 1.27)) hide)
    )
    (property "Datasheet" "" (at 238.76 92.71 0)
      (effects (font (size 1.27 1.27)) hide)
    )
    (pin "1")
    (instances
      (project "data-center-rdimm-ddr4-tester"
        (path ""
          (reference "#PWR0395") (unit 1)
        )
      )
    )
  )

  (symbol (lib_id "antmicroResistors0402:R_330R_0402") (at 214.63 238.125 270) (unit 1)
    (in_bom yes) (on_board yes) (dnp no) (fields_autoplaced)
    (property "Reference" "R189" (at 217.17 239.395 90)
      (effects (font (size 1.524 1.524)) (justify left))
    )
    (property "Value" "R_330R_0402" (at 201.93 258.445 0)
      (effects (font (size 1.27 1.27) (thickness 0.15)) (justify left bottom) hide)
    )
    (property "Footprint" "antmicro-footprints:R_0402_1005Metric" (at 199.39 258.445 0)
      (effects (font (size 1.27 1.27) (thickness 0.15)) (justify left bottom) hide)
    )
    (property "Datasheet" "https://www.bourns.com/docs/product-datasheets/cr.pdf" (at 196.85 258.445 0)
      (effects (font (size 1.27 1.27) (thickness 0.15)) (justify left bottom) hide)
    )
    (property "Manufacturer" "Bourns" (at 191.77 258.445 0)
      (effects (font (size 1.27 1.27) (thickness 0.15)) (justify left bottom) hide)
    )
    (property "MPN" "CR0402-FX-3300GLF" (at 194.31 258.445 0)
      (effects (font (size 1.27 1.27) (thickness 0.15)) (justify left bottom) hide)
    )
    (property "Val" "330R" (at 217.17 242.5699 90)
      (effects (font (size 1.27 1.27) (thickness 0.15)) (justify left))
    )
    (property "License" "Apache-2.0" (at 189.23 258.445 0)
      (effects (font (size 1.27 1.27) (thickness 0.15)) (justify left bottom) hide)
    )
    (property "Author" "Antmicro" (at 186.69 258.445 0)
      (effects (font (size 1.27 1.27) (thickness 0.15)) (justify left bottom) hide)
    )
    (property "Tolerance" "1%" (at 204.47 258.445 0)
      (effects (font (size 1.27 1.27)) (justify left bottom) hide)
    )
    (pin "1")
    (pin "2")
    (instances
      (project "data-center-rdimm-ddr4-tester"
        (path ""
          (reference "R189") (unit 1)
        )
      )
    )
  )

  (symbol (lib_id "antmicroCapacitors0402:C_1u_0402") (at 267.335 250.825 270) (unit 1)
    (in_bom no) (on_board yes) (dnp yes)
    (property "Reference" "C226" (at 270.51 252.095 90)
      (effects (font (size 1.524 1.524)) (justify left))
    )
    (property "Value" "C_1u_0402" (at 257.175 271.145 0)
      (effects (font (size 1.27 1.27) (thickness 0.15)) (justify left bottom) hide)
    )
    (property "Footprint" "antmicro-footprints:C_0402_1005Metric" (at 254.635 271.145 0)
      (effects (font (size 1.27 1.27) (thickness 0.15)) (justify left bottom) hide)
    )
    (property "Datasheet" " " (at 252.095 271.145 0)
      (effects (font (size 1.27 1.27) (thickness 0.15)) (justify left bottom) hide)
    )
    (property "Manufacturer" "TDK" (at 247.015 271.145 0)
      (effects (font (size 1.27 1.27) (thickness 0.15)) (justify left bottom) hide)
    )
    (property "MPN" "C1005X6S1A105K050BC" (at 249.555 271.145 0)
      (effects (font (size 1.27 1.27) (thickness 0.15)) (justify left bottom) hide)
    )
    (property "Val" "1u" (at 270.51 254.0062 90)
      (effects (font (size 1.27 1.27) (thickness 0.15)) (justify left))
    )
    (property "License" "Apache-2.0" (at 244.475 271.145 0)
      (effects (font (size 1.27 1.27) (thickness 0.15)) (justify left bottom) hide)
    )
    (property "Author" "Antmicro" (at 241.935 271.145 0)
      (effects (font (size 1.27 1.27) (thickness 0.15)) (justify left bottom) hide)
    )
    (property "Voltage" "" (at 239.395 271.145 0)
      (effects (font (size 1.27 1.27)) (justify left bottom) hide)
    )
    (property "Dielectric" "" (at 236.855 271.145 0)
      (effects (font (size 1.27 1.27)) (justify left bottom) hide)
    )
    (property "DNP" "DNP" (at 270.51 255.905 90)
      (effects (font (size 1.27 1.27)) (justify left))
    )
    (pin "1")
    (pin "2")
    (instances
      (project "data-center-rdimm-ddr4-tester"
        (path ""
          (reference "C226") (unit 1)
        )
      )
    )
  )

  (symbol (lib_id "antmicroResistors0402:R_330R_0402") (at 379.095 87.63 0) (unit 1)
    (in_bom yes) (on_board yes) (dnp no)
    (property "Reference" "R147" (at 381.635 82.55 0)
      (effects (font (size 1.524 1.524)))
    )
    (property "Value" "R_330R_0402" (at 399.415 100.33 0)
      (effects (font (size 1.27 1.27) (thickness 0.15)) (justify left bottom) hide)
    )
    (property "Footprint" "antmicro-footprints:R_0402_1005Metric" (at 399.415 102.87 0)
      (effects (font (size 1.27 1.27) (thickness 0.15)) (justify left bottom) hide)
    )
    (property "Datasheet" "https://www.bourns.com/docs/product-datasheets/cr.pdf" (at 399.415 105.41 0)
      (effects (font (size 1.27 1.27) (thickness 0.15)) (justify left bottom) hide)
    )
    (property "Manufacturer" "Bourns" (at 399.415 110.49 0)
      (effects (font (size 1.27 1.27) (thickness 0.15)) (justify left bottom) hide)
    )
    (property "MPN" "CR0402-FX-3300GLF" (at 399.415 107.95 0)
      (effects (font (size 1.27 1.27) (thickness 0.15)) (justify left bottom) hide)
    )
    (property "Val" "330R" (at 381.635 85.09 0)
      (effects (font (size 1.27 1.27) (thickness 0.15)))
    )
    (property "License" "Apache-2.0" (at 399.415 113.03 0)
      (effects (font (size 1.27 1.27) (thickness 0.15)) (justify left bottom) hide)
    )
    (property "Author" "Antmicro" (at 399.415 115.57 0)
      (effects (font (size 1.27 1.27) (thickness 0.15)) (justify left bottom) hide)
    )
    (property "Tolerance" "1%" (at 399.415 97.79 0)
      (effects (font (size 1.27 1.27)) (justify left bottom) hide)
    )
    (pin "1")
    (pin "2")
    (instances
      (project "data-center-rdimm-ddr4-tester"
        (path ""
          (reference "R147") (unit 1)
        )
      )
    )
  )

  (symbol (lib_id "antmicroLEDIndicationDiscrete:LED_RGY_0606_APTF1616SURKCGKSYKC") (at 152.4 229.87 0) (unit 1)
    (in_bom yes) (on_board yes) (dnp no) (fields_autoplaced)
    (property "Reference" "D17" (at 161.925 222.25 0)
      (effects (font (size 1.27 1.27)))
    )
    (property "Value" "LED_RGY_0606_APTF1616SURKCGKSYKC" (at 161.925 224.79 0)
      (effects (font (size 1.27 1.27) (thickness 0.15)))
    )
    (property "Footprint" "antmicro-footprints:LED_RGY_1.6x1.6mm_APTF1616" (at 185.42 238.76 0)
      (effects (font (size 1.27 1.27) (thickness 0.15)) (justify left bottom) hide)
    )
    (property "Datasheet" "http://www.mouser.com/datasheet/2/216/APTF1616SURKCGKSYKC-1145193.pdf" (at 185.42 241.3 0)
      (effects (font (size 1.27 1.27) (thickness 0.15)) (justify left bottom) hide)
    )
    (property "MPN" "APTF1616SURKCGKSYKC" (at 185.42 246.38 0)
      (effects (font (size 1.27 1.27) (thickness 0.15)) (justify left bottom) hide)
    )
    (property "Manufacturer" "Kingbright" (at 185.42 248.92 0)
      (effects (font (size 1.27 1.27) (thickness 0.15)) (justify left bottom) hide)
    )
    (property "Description" "Standard LEDs - SMD RGY 1616 SMD" (at 185.42 243.84 0)
      (effects (font (size 1.27 1.27) (thickness 0.15)) (justify left bottom) hide)
    )
    (property "Author" "Antmicro" (at 185.42 251.46 0)
      (effects (font (size 1.27 1.27) (thickness 0.15)) (justify left bottom) hide)
    )
    (property "License" "Apache-2.0" (at 185.42 254 0)
      (effects (font (size 1.27 1.27) (thickness 0.15)) (justify left bottom) hide)
    )
    (pin "1")
    (pin "2")
    (pin "3")
    (pin "4")
    (instances
      (project "data-center-rdimm-ddr4-tester"
        (path ""
          (reference "D17") (unit 1)
        )
      )
    )
  )

  (symbol (lib_id "antmicroResistors0402:R_330R_0402") (at 196.85 238.125 270) (unit 1)
    (in_bom yes) (on_board yes) (dnp no) (fields_autoplaced)
    (property "Reference" "R188" (at 199.39 239.395 90)
      (effects (font (size 1.524 1.524)) (justify left))
    )
    (property "Value" "R_330R_0402" (at 184.15 258.445 0)
      (effects (font (size 1.27 1.27) (thickness 0.15)) (justify left bottom) hide)
    )
    (property "Footprint" "antmicro-footprints:R_0402_1005Metric" (at 181.61 258.445 0)
      (effects (font (size 1.27 1.27) (thickness 0.15)) (justify left bottom) hide)
    )
    (property "Datasheet" "https://www.bourns.com/docs/product-datasheets/cr.pdf" (at 179.07 258.445 0)
      (effects (font (size 1.27 1.27) (thickness 0.15)) (justify left bottom) hide)
    )
    (property "Manufacturer" "Bourns" (at 173.99 258.445 0)
      (effects (font (size 1.27 1.27) (thickness 0.15)) (justify left bottom) hide)
    )
    (property "MPN" "CR0402-FX-3300GLF" (at 176.53 258.445 0)
      (effects (font (size 1.27 1.27) (thickness 0.15)) (justify left bottom) hide)
    )
    (property "Val" "330R" (at 199.39 242.5699 90)
      (effects (font (size 1.27 1.27) (thickness 0.15)) (justify left))
    )
    (property "License" "Apache-2.0" (at 171.45 258.445 0)
      (effects (font (size 1.27 1.27) (thickness 0.15)) (justify left bottom) hide)
    )
    (property "Author" "Antmicro" (at 168.91 258.445 0)
      (effects (font (size 1.27 1.27) (thickness 0.15)) (justify left bottom) hide)
    )
    (property "Tolerance" "1%" (at 186.69 258.445 0)
      (effects (font (size 1.27 1.27)) (justify left bottom) hide)
    )
    (pin "1")
    (pin "2")
    (instances
      (project "data-center-rdimm-ddr4-tester"
        (path ""
          (reference "R188") (unit 1)
        )
      )
    )
  )

  (symbol (lib_id "data-center-rdimm-ddr4-tester:USB-C_USB4105-GF-A") (at 237.49 152.4 0) (unit 1)
    (in_bom yes) (on_board yes) (dnp no) (fields_autoplaced)
    (property "Reference" "J9" (at 256.54 166.3699 0)
      (effects (font (size 1.27 1.27)) (justify left))
    )
    (property "Value" "USB-C_USB4105-GF-A" (at 256.54 168.9099 0)
      (effects (font (size 1.27 1.27) (thickness 0.15)) (justify left) hide)
    )
    (property "Footprint" "data-center-rdimm-ddr4-tester-footprints:USB-C_GCT_USB4105-GF-A" (at 275.59 160.02 0)
      (effects (font (size 1.27 1.27) (thickness 0.15)) (justify left bottom) hide)
    )
    (property "Datasheet" "https://gct.co/files/drawings/usb4105.pdf" (at 275.59 162.56 0)
      (effects (font (size 1.27 1.27) (thickness 0.15)) (justify left bottom) hide)
    )
    (property "MPN" "USB4105-GF-A" (at 256.54 168.9099 0)
      (effects (font (size 1.27 1.27) (thickness 0.15)) (justify left))
    )
    (property "Manufacturer" "GCT" (at 275.59 165.1 0)
      (effects (font (size 1.27 1.27) (thickness 0.15)) (justify left bottom) hide)
    )
    (property "Author" "Antmicro" (at 275.59 170.18 0)
      (effects (font (size 1.27 1.27) (thickness 0.15)) (justify left bottom) hide)
    )
    (property "License" "Apache-2.0" (at 275.59 172.72 0)
      (effects (font (size 1.27 1.27) (thickness 0.15)) (justify left bottom) hide)
    )
    (pin "A1")
    (pin "A12")
    (pin "A4")
    (pin "A5")
    (pin "A6")
    (pin "A7")
    (pin "A8")
    (pin "A9")
    (pin "B1")
    (pin "B12")
    (pin "B4")
    (pin "B5")
    (pin "B6")
    (pin "B7")
    (pin "B8")
    (pin "B9")
    (pin "SH")
    (instances
      (project "data-center-rdimm-ddr4-tester"
        (path ""
          (reference "J9") (unit 1)
        )
      )
    )
  )

  (symbol (lib_id "antmicropower:GNDS") (at 387.35 69.85 0) (unit 1)
    (in_bom yes) (on_board yes) (dnp no) (fields_autoplaced)
    (property "Reference" "#PWR0394" (at 387.35 76.2 0)
      (effects (font (size 1.27 1.27)) hide)
    )
    (property "Value" "GNDS" (at 387.35 74.93 0)
      (effects (font (size 1.27 1.27)))
    )
    (property "Footprint" "" (at 387.35 69.85 0)
      (effects (font (size 1.27 1.27)) hide)
    )
    (property "Datasheet" "" (at 387.35 69.85 0)
      (effects (font (size 1.27 1.27)) hide)
    )
    (pin "1")
    (instances
      (project "data-center-rdimm-ddr4-tester"
        (path ""
          (reference "#PWR0394") (unit 1)
        )
      )
    )
  )

  (symbol (lib_id "antmicroCapacitors0402:C_100n_0402") (at 384.175 99.06 180) (unit 1)
    (in_bom yes) (on_board yes) (dnp no)
    (property "Reference" "C311" (at 381.6414 93.345 0)
      (effects (font (size 1.524 1.524)))
    )
    (property "Value" "C_100n_0402" (at 363.855 88.9 0)
      (effects (font (size 1.27 1.27) (thickness 0.15)) (justify left bottom) hide)
    )
    (property "Footprint" "antmicro-footprints:C_0402_1005Metric" (at 363.855 86.36 0)
      (effects (font (size 1.27 1.27) (thickness 0.15)) (justify left bottom) hide)
    )
    (property "Datasheet" "https://search.murata.co.jp/Ceramy/image/img/A01X/G101/ENG/GRM155R61H104KE14-01.pdf" (at 363.855 83.82 0)
      (effects (font (size 1.27 1.27) (thickness 0.15)) (justify left bottom) hide)
    )
    (property "Manufacturer" "Murata" (at 363.855 78.74 0)
      (effects (font (size 1.27 1.27) (thickness 0.15)) (justify left bottom) hide)
    )
    (property "MPN" "GRM155R61H104KE14D" (at 363.855 81.28 0)
      (effects (font (size 1.27 1.27) (thickness 0.15)) (justify left bottom) hide)
    )
    (property "Val" "100n" (at 381.635 95.885 0)
      (effects (font (size 1.27 1.27) (thickness 0.15)))
    )
    (property "License" "Apache-2.0" (at 363.855 76.2 0)
      (effects (font (size 1.27 1.27) (thickness 0.15)) (justify left bottom) hide)
    )
    (property "Author" "Antmicro" (at 363.855 73.66 0)
      (effects (font (size 1.27 1.27) (thickness 0.15)) (justify left bottom) hide)
    )
    (property "Voltage" "50V" (at 363.855 71.12 0)
      (effects (font (size 1.27 1.27)) (justify left bottom) hide)
    )
    (property "Dielectric" "X5R" (at 363.855 68.58 0)
      (effects (font (size 1.27 1.27)) (justify left bottom) hide)
    )
    (pin "1")
    (pin "2")
    (instances
      (project "data-center-rdimm-ddr4-tester"
        (path ""
          (reference "C311") (unit 1)
        )
      )
    )
  )

  (symbol (lib_id "antmicropower:GND") (at 375.92 101.6 0) (unit 1)
    (in_bom yes) (on_board yes) (dnp no) (fields_autoplaced)
    (property "Reference" "#PWR0392" (at 375.92 107.95 0)
      (effects (font (size 1.27 1.27)) hide)
    )
    (property "Value" "GND" (at 375.92 106.68 0)
      (effects (font (size 1.27 1.27)))
    )
    (property "Footprint" "" (at 375.92 101.6 0)
      (effects (font (size 1.27 1.27)) hide)
    )
    (property "Datasheet" "" (at 375.92 101.6 0)
      (effects (font (size 1.27 1.27)) hide)
    )
    (property "Author" "Antmicro" (at 384.81 109.22 0)
      (effects (font (size 1.27 1.27) (thickness 0.15)) (justify left bottom) hide)
    )
    (property "License" "Apache-2.0" (at 384.81 111.76 0)
      (effects (font (size 1.27 1.27) (thickness 0.15)) (justify left bottom) hide)
    )
    (pin "1")
    (instances
      (project "data-center-rdimm-ddr4-tester"
        (path ""
          (reference "#PWR0392") (unit 1)
        )
      )
    )
  )

  (symbol (lib_id "antmicropower:GND") (at 219.075 160.02 270) (unit 1)
    (in_bom yes) (on_board yes) (dnp no) (fields_autoplaced)
    (property "Reference" "#PWR0105" (at 212.725 160.02 0)
      (effects (font (size 1.27 1.27)) hide)
    )
    (property "Value" "GND" (at 215.9 160.0199 90)
      (effects (font (size 1.27 1.27)) (justify right))
    )
    (property "Footprint" "" (at 219.075 160.02 0)
      (effects (font (size 1.27 1.27)) hide)
    )
    (property "Datasheet" "" (at 219.075 160.02 0)
      (effects (font (size 1.27 1.27)) hide)
    )
    (property "Author" "Antmicro" (at 211.455 168.91 0)
      (effects (font (size 1.27 1.27) (thickness 0.15)) (justify left bottom) hide)
    )
    (property "License" "Apache-2.0" (at 208.915 168.91 0)
      (effects (font (size 1.27 1.27) (thickness 0.15)) (justify left bottom) hide)
    )
    (pin "1")
    (instances
      (project "data-center-rdimm-ddr4-tester"
        (path ""
          (reference "#PWR0105") (unit 1)
        )
      )
    )
  )

  (symbol (lib_id "antmicroPushbuttonSwitches:SW_1-1825027-1_THT") (at 259.08 246.38 270) (unit 1)
    (in_bom yes) (on_board yes) (dnp no)
    (property "Reference" "S1" (at 252.73 250.19 90)
      (effects (font (size 1.524 1.524)) (justify left))
    )
    (property "Value" "SW_1-1825027-1" (at 253.365 253.3649 90)
      (effects (font (size 1.27 1.27) (thickness 0.15)) (justify right) hide)
    )
    (property "Footprint" "antmicro-footprints:SW_1-1825027-1_THT" (at 248.92 271.78 0)
      (effects (font (size 1.27 1.27) (thickness 0.15)) (justify left bottom) hide)
    )
    (property "Datasheet" "https://www.te.com/commerce/DocumentDelivery/DDEController?Action=showdoc&DocId=Customer+Drawing%7F1825027%7FH1%7Fpdf%7FEnglish%7FENG_CD_1825027_H1.pdf%7F1-1825027-1" (at 246.38 271.78 0)
      (effects (font (size 1.27 1.27) (thickness 0.15)) (justify left bottom) hide)
    )
    (property "MPN" "1-1825027-1" (at 241.3 252.73 90)
      (effects (font (size 1.27 1.27) (thickness 0.15)) (justify left))
    )
    (property "Manufacturer" "TE Connectivity" (at 241.3 271.78 0)
      (effects (font (size 1.27 1.27) (thickness 0.15)) (justify left bottom) hide)
    )
    (property "Author" "Antmicro" (at 238.76 271.78 0)
      (effects (font (size 1.27 1.27) (thickness 0.15)) (justify left bottom) hide)
    )
    (property "License" "Apache-2.0" (at 236.22 271.78 0)
      (effects (font (size 1.27 1.27) (thickness 0.15)) (justify left bottom) hide)
    )
    (pin "1")
    (pin "2")
    (pin "SH")
    (instances
      (project "data-center-rdimm-ddr4-tester"
        (path ""
          (reference "S1") (unit 1)
        )
      )
    )
  )

  (symbol (lib_id "antmicroTransistorsFETsMOSFETsSingle:BSS138PW") (at 170.18 273.685 0) (unit 1)
    (in_bom yes) (on_board yes) (dnp no) (fields_autoplaced)
    (property "Reference" "Q1" (at 181.61 269.875 0)
      (effects (font (size 1.524 1.524)) (justify left))
    )
    (property "Value" "BSS138PW" (at 181.61 273.0499 0)
      (effects (font (size 1.27 1.27) (thickness 0.15)) (justify left))
    )
    (property "Footprint" "antmicro-footprints:SC70-3" (at 193.04 285.115 0)
      (effects (font (size 1.27 1.27) (thickness 0.15)) (justify left bottom) hide)
    )
    (property "Datasheet" "https://assets.nexperia.com/documents/data-sheet/BSS138PW.pdf" (at 193.04 287.655 0)
      (effects (font (size 1.27 1.27) (thickness 0.15)) (justify left bottom) hide)
    )
    (property "MPN" "BSS138PW" (at 193.04 290.195 0)
      (effects (font (size 1.27 1.27) (thickness 0.15)) (justify left bottom) hide)
    )
    (property "Manufacturer" "Nexperia" (at 193.04 292.735 0)
      (effects (font (size 1.27 1.27) (thickness 0.15)) (justify left bottom) hide)
    )
    (property "Author" "Antmicro" (at 193.04 295.275 0)
      (effects (font (size 1.27 1.27) (thickness 0.15)) (justify left bottom) hide)
    )
    (property "License" "Apache-2.0" (at 193.04 297.815 0)
      (effects (font (size 1.27 1.27) (thickness 0.15)) (justify left bottom) hide)
    )
    (pin "1")
    (pin "2")
    (pin "3")
    (instances
      (project "data-center-rdimm-ddr4-tester"
        (path ""
          (reference "Q1") (unit 1)
        )
      )
    )
  )

  (symbol (lib_id "antmicroTestPoints:TP_1mm_SMD") (at 227.33 152.4 180) (unit 1)
    (in_bom yes) (on_board yes) (dnp no)
    (property "Reference" "VBUS1" (at 219.71 152.4 0)
      (effects (font (size 1.27 1.27)))
    )
    (property "Value" "TP_1mm_SMD" (at 212.09 144.78 0)
      (effects (font (size 1.27 1.27) (thickness 0.15)) (justify left bottom) hide)
    )
    (property "Footprint" "antmicro-footprints:TP_SMD_1mm" (at 212.09 142.24 0)
      (effects (font (size 1.27 1.27) (thickness 0.15)) (justify left bottom) hide)
    )
    (property "Datasheet" "" (at 212.09 139.7 0)
      (effects (font (size 1.27 1.27) (thickness 0.15)) (justify left bottom) hide)
    )
    (property "MPN" "" (at 227.33 152.4 0)
      (effects (font (size 1.27 1.27)) hide)
    )
    (property "Manufacturer" "" (at 227.33 152.4 0)
      (effects (font (size 1.27 1.27)) hide)
    )
    (property "Author" "Antmicro" (at 212.09 137.16 0)
      (effects (font (size 1.27 1.27) (thickness 0.15)) (justify left bottom) hide)
    )
    (property "License" "Apache-2.0" (at 212.09 134.62 0)
      (effects (font (size 1.27 1.27) (thickness 0.15)) (justify left bottom) hide)
    )
    (pin "1")
    (instances
      (project "data-center-rdimm-ddr4-tester"
        (path ""
          (reference "VBUS1") (unit 1)
        )
      )
    )
  )

  (symbol (lib_id "antmicropower:GND1") (at 387.35 101.6 0) (unit 1)
    (in_bom yes) (on_board yes) (dnp no) (fields_autoplaced)
    (property "Reference" "#PWR0393" (at 387.35 107.95 0)
      (effects (font (size 1.27 1.27)) hide)
    )
    (property "Value" "GND1" (at 387.35 106.68 0)
      (effects (font (size 1.27 1.27)))
    )
    (property "Footprint" "" (at 387.35 101.6 0)
      (effects (font (size 1.27 1.27)) hide)
    )
    (property "Datasheet" "" (at 387.35 101.6 0)
      (effects (font (size 1.27 1.27)) hide)
    )
    (pin "1")
    (instances
      (project "data-center-rdimm-ddr4-tester"
        (path ""
          (reference "#PWR0393") (unit 1)
        )
      )
    )
  )

  (symbol (lib_id "antmicropower:GND") (at 177.8 277.495 0) (unit 1)
    (in_bom yes) (on_board yes) (dnp no) (fields_autoplaced)
    (property "Reference" "#PWR0323" (at 177.8 283.845 0)
      (effects (font (size 1.27 1.27)) hide)
    )
    (property "Value" "GND" (at 177.8 281.94 0)
      (effects (font (size 1.27 1.27)))
    )
    (property "Footprint" "" (at 177.8 277.495 0)
      (effects (font (size 1.27 1.27)) hide)
    )
    (property "Datasheet" "" (at 177.8 277.495 0)
      (effects (font (size 1.27 1.27)) hide)
    )
    (property "Author" "Antmicro" (at 186.69 285.115 0)
      (effects (font (size 1.27 1.27) (thickness 0.15)) (justify left bottom) hide)
    )
    (property "License" "Apache-2.0" (at 186.69 287.655 0)
      (effects (font (size 1.27 1.27) (thickness 0.15)) (justify left bottom) hide)
    )
    (pin "1")
    (instances
      (project "data-center-rdimm-ddr4-tester"
        (path ""
          (reference "#PWR0323") (unit 1)
        )
      )
    )
  )

  (symbol (lib_id "antmicroResistors0402:R_330R_0402") (at 379.095 55.88 0) (unit 1)
    (in_bom yes) (on_board yes) (dnp no)
    (property "Reference" "R125" (at 381.635 50.8 0)
      (effects (font (size 1.524 1.524)))
    )
    (property "Value" "R_330R_0402" (at 399.415 68.58 0)
      (effects (font (size 1.27 1.27) (thickness 0.15)) (justify left bottom) hide)
    )
    (property "Footprint" "antmicro-footprints:R_0402_1005Metric" (at 399.415 71.12 0)
      (effects (font (size 1.27 1.27) (thickness 0.15)) (justify left bottom) hide)
    )
    (property "Datasheet" "https://www.bourns.com/docs/product-datasheets/cr.pdf" (at 399.415 73.66 0)
      (effects (font (size 1.27 1.27) (thickness 0.15)) (justify left bottom) hide)
    )
    (property "Manufacturer" "Bourns" (at 399.415 78.74 0)
      (effects (font (size 1.27 1.27) (thickness 0.15)) (justify left bottom) hide)
    )
    (property "MPN" "CR0402-FX-3300GLF" (at 399.415 76.2 0)
      (effects (font (size 1.27 1.27) (thickness 0.15)) (justify left bottom) hide)
    )
    (property "Val" "330R" (at 381.635 53.34 0)
      (effects (font (size 1.27 1.27) (thickness 0.15)))
    )
    (property "License" "Apache-2.0" (at 399.415 81.28 0)
      (effects (font (size 1.27 1.27) (thickness 0.15)) (justify left bottom) hide)
    )
    (property "Author" "Antmicro" (at 399.415 83.82 0)
      (effects (font (size 1.27 1.27) (thickness 0.15)) (justify left bottom) hide)
    )
    (property "Tolerance" "1%" (at 399.415 66.04 0)
      (effects (font (size 1.27 1.27)) (justify left bottom) hide)
    )
    (pin "1")
    (pin "2")
    (instances
      (project "data-center-rdimm-ddr4-tester"
        (path ""
          (reference "R125") (unit 1)
        )
      )
    )
  )

  (symbol (lib_id "antmicropower:GND") (at 375.92 69.85 0) (unit 1)
    (in_bom yes) (on_board yes) (dnp no) (fields_autoplaced)
    (property "Reference" "#PWR0391" (at 375.92 76.2 0)
      (effects (font (size 1.27 1.27)) hide)
    )
    (property "Value" "GND" (at 375.92 74.93 0)
      (effects (font (size 1.27 1.27)))
    )
    (property "Footprint" "" (at 375.92 69.85 0)
      (effects (font (size 1.27 1.27)) hide)
    )
    (property "Datasheet" "" (at 375.92 69.85 0)
      (effects (font (size 1.27 1.27)) hide)
    )
    (property "Author" "Antmicro" (at 384.81 77.47 0)
      (effects (font (size 1.27 1.27) (thickness 0.15)) (justify left bottom) hide)
    )
    (property "License" "Apache-2.0" (at 384.81 80.01 0)
      (effects (font (size 1.27 1.27) (thickness 0.15)) (justify left bottom) hide)
    )
    (pin "1")
    (instances
      (project "data-center-rdimm-ddr4-tester"
        (path ""
          (reference "#PWR0391") (unit 1)
        )
      )
    )
  )

  (symbol (lib_id "antmicropower:GNDS") (at 235.585 184.785 0) (unit 1)
    (in_bom yes) (on_board yes) (dnp no) (fields_autoplaced)
    (property "Reference" "#PWR0178" (at 235.585 191.135 0)
      (effects (font (size 1.27 1.27)) hide)
    )
    (property "Value" "GNDS" (at 235.585 189.23 0)
      (effects (font (size 1.27 1.27)))
    )
    (property "Footprint" "" (at 235.585 184.785 0)
      (effects (font (size 1.27 1.27)) hide)
    )
    (property "Datasheet" "" (at 235.585 184.785 0)
      (effects (font (size 1.27 1.27)) hide)
    )
    (pin "1")
    (instances
      (project "data-center-rdimm-ddr4-tester"
        (path ""
          (reference "#PWR0178") (unit 1)
        )
      )
    )
  )

  (symbol (lib_id "antmicropower:GND") (at 259.08 265.43 0) (unit 1)
    (in_bom yes) (on_board yes) (dnp no) (fields_autoplaced)
    (property "Reference" "#PWR0324" (at 259.08 271.78 0)
      (effects (font (size 1.27 1.27)) hide)
    )
    (property "Value" "GND" (at 259.08 270.51 0)
      (effects (font (size 1.27 1.27)))
    )
    (property "Footprint" "" (at 259.08 265.43 0)
      (effects (font (size 1.27 1.27)) hide)
    )
    (property "Datasheet" "" (at 259.08 265.43 0)
      (effects (font (size 1.27 1.27)) hide)
    )
    (property "Author" "Antmicro" (at 267.97 273.05 0)
      (effects (font (size 1.27 1.27) (thickness 0.15)) (justify left bottom) hide)
    )
    (property "License" "Apache-2.0" (at 267.97 275.59 0)
      (effects (font (size 1.27 1.27) (thickness 0.15)) (justify left bottom) hide)
    )
    (pin "1")
    (instances
      (project "data-center-rdimm-ddr4-tester"
        (path ""
          (reference "#PWR0324") (unit 1)
        )
      )
    )
  )

  (symbol (lib_id "antmicropower:GND") (at 196.85 277.495 0) (unit 1)
    (in_bom yes) (on_board yes) (dnp no) (fields_autoplaced)
    (property "Reference" "#PWR0321" (at 196.85 283.845 0)
      (effects (font (size 1.27 1.27)) hide)
    )
    (property "Value" "GND" (at 196.85 282.575 0)
      (effects (font (size 1.27 1.27)))
    )
    (property "Footprint" "" (at 196.85 277.495 0)
      (effects (font (size 1.27 1.27)) hide)
    )
    (property "Datasheet" "" (at 196.85 277.495 0)
      (effects (font (size 1.27 1.27)) hide)
    )
    (property "Author" "Antmicro" (at 205.74 285.115 0)
      (effects (font (size 1.27 1.27) (thickness 0.15)) (justify left bottom) hide)
    )
    (property "License" "Apache-2.0" (at 205.74 287.655 0)
      (effects (font (size 1.27 1.27) (thickness 0.15)) (justify left bottom) hide)
    )
    (pin "1")
    (instances
      (project "data-center-rdimm-ddr4-tester"
        (path ""
          (reference "#PWR0321") (unit 1)
        )
      )
    )
  )

  (symbol (lib_id "antmicropower:GND") (at 214.63 277.495 0) (unit 1)
    (in_bom yes) (on_board yes) (dnp no) (fields_autoplaced)
    (property "Reference" "#PWR0322" (at 214.63 283.845 0)
      (effects (font (size 1.27 1.27)) hide)
    )
    (property "Value" "GND" (at 214.63 282.575 0)
      (effects (font (size 1.27 1.27)))
    )
    (property "Footprint" "" (at 214.63 277.495 0)
      (effects (font (size 1.27 1.27)) hide)
    )
    (property "Datasheet" "" (at 214.63 277.495 0)
      (effects (font (size 1.27 1.27)) hide)
    )
    (property "Author" "Antmicro" (at 223.52 285.115 0)
      (effects (font (size 1.27 1.27) (thickness 0.15)) (justify left bottom) hide)
    )
    (property "License" "Apache-2.0" (at 223.52 287.655 0)
      (effects (font (size 1.27 1.27) (thickness 0.15)) (justify left bottom) hide)
    )
    (pin "1")
    (instances
      (project "data-center-rdimm-ddr4-tester"
        (path ""
          (reference "#PWR0322") (unit 1)
        )
      )
    )
  )

  (symbol (lib_id "antmicroTransistorsFETsMOSFETsSingle:BSS138PW") (at 207.01 253.365 0) (unit 1)
    (in_bom yes) (on_board yes) (dnp no) (fields_autoplaced)
    (property "Reference" "Q10" (at 218.44 249.555 0)
      (effects (font (size 1.524 1.524)) (justify left))
    )
    (property "Value" "BSS138PW" (at 218.44 252.7299 0)
      (effects (font (size 1.27 1.27) (thickness 0.15)) (justify left))
    )
    (property "Footprint" "antmicro-footprints:SC70-3" (at 229.87 264.795 0)
      (effects (font (size 1.27 1.27) (thickness 0.15)) (justify left bottom) hide)
    )
    (property "Datasheet" "https://assets.nexperia.com/documents/data-sheet/BSS138PW.pdf" (at 229.87 267.335 0)
      (effects (font (size 1.27 1.27) (thickness 0.15)) (justify left bottom) hide)
    )
    (property "MPN" "BSS138PW" (at 229.87 269.875 0)
      (effects (font (size 1.27 1.27) (thickness 0.15)) (justify left bottom) hide)
    )
    (property "Manufacturer" "Nexperia" (at 229.87 272.415 0)
      (effects (font (size 1.27 1.27) (thickness 0.15)) (justify left bottom) hide)
    )
    (property "Author" "Antmicro" (at 229.87 274.955 0)
      (effects (font (size 1.27 1.27) (thickness 0.15)) (justify left bottom) hide)
    )
    (property "License" "Apache-2.0" (at 229.87 277.495 0)
      (effects (font (size 1.27 1.27) (thickness 0.15)) (justify left bottom) hide)
    )
    (pin "1")
    (pin "2")
    (pin "3")
    (instances
      (project "data-center-rdimm-ddr4-tester"
        (path ""
          (reference "Q10") (unit 1)
        )
      )
    )
  )

  (symbol (lib_id "antmicroInterfaceControllers:FT4232H_VQFN") (at 80.645 50.8 0) (unit 1)
    (in_bom yes) (on_board yes) (dnp no) (fields_autoplaced)
    (property "Reference" "U7" (at 100.965 41.91 0)
      (effects (font (size 1.524 1.524)))
    )
    (property "Value" "FT4232H_VQFN" (at 100.965 45.72 0)
      (effects (font (size 1.27 1.27) (thickness 0.15)))
    )
    (property "Footprint" "antmicro-footprints:QFN-56-1EP_8x8mm_P0.5mm" (at 136.525 58.42 0)
      (effects (font (size 1.27 1.27) (thickness 0.15)) (justify left bottom) hide)
    )
    (property "Datasheet" "https://www.ftdichip.com/Support/Documents/DataSheets/ICs/DS_FT4232H.pdf" (at 136.525 60.96 0)
      (effects (font (size 1.27 1.27) (thickness 0.15)) (justify left bottom) hide)
    )
    (property "Manufacturer" "FTDI Chip" (at 136.525 63.5 0)
      (effects (font (size 1.27 1.27) (thickness 0.15)) (justify left bottom) hide)
    )
    (property "MPN" "FT4232H-56Q-REEL" (at 136.525 66.04 0)
      (effects (font (size 1.27 1.27) (thickness 0.15)) (justify left bottom) hide)
    )
    (property "Author" "Antmicro" (at 136.525 68.58 0)
      (effects (font (size 1.27 1.27) (thickness 0.15)) (justify left bottom) hide)
    )
    (property "License" "Apache-2.0" (at 136.525 71.12 0)
      (effects (font (size 1.27 1.27) (thickness 0.15)) (justify left bottom) hide)
    )
    (pin "1")
    (pin "10")
    (pin "11")
    (pin "12")
    (pin "13")
    (pin "14")
    (pin "15")
    (pin "16")
    (pin "17")
    (pin "18")
    (pin "19")
    (pin "2")
    (pin "20")
    (pin "21")
    (pin "22")
    (pin "23")
    (pin "24")
    (pin "25")
    (pin "26")
    (pin "27")
    (pin "28")
    (pin "29")
    (pin "3")
    (pin "30")
    (pin "31")
    (pin "32")
    (pin "33")
    (pin "34")
    (pin "35")
    (pin "36")
    (pin "37")
    (pin "38")
    (pin "39")
    (pin "4")
    (pin "40")
    (pin "41")
    (pin "42")
    (pin "43")
    (pin "44")
    (pin "45")
    (pin "46")
    (pin "47")
    (pin "48")
    (pin "49")
    (pin "5")
    (pin "50")
    (pin "51")
    (pin "52")
    (pin "53")
    (pin "54")
    (pin "55")
    (pin "56")
    (pin "57")
    (pin "6")
    (pin "7")
    (pin "8")
    (pin "9")
    (instances
      (project "data-center-rdimm-ddr4-tester"
        (path ""
          (reference "U7") (unit 1)
        )
      )
    )
  )
)
